FILE_TYPE = MACRO_DRAWING;
SET COLOR_WIRE YELLOW;
SET COLOR_PROP ORANGE;
SET COLOR_DOT WHITE;
SET COLOR_ARC YELLOW;
SET COLOR_BODY GREEN;
SET COLOR_NOTE PURPLE;
SET PROP_DISPLAY VALUE;
SET PAGE_NUMBER P297;
FORCEADD OFFPAGE..1
(-1575 -700);
FORCEPROP 2 LAST $XR0 85 
J 0
(-1796 -700);
DISPLAY 0.638298 (-1796 -700);
PAINT MONO (-1796 -700);
FORCEPROP 2 LAST CDS_LIB standard
J 0
(-1575 -700);
DISPLAY INVISIBLE (-1575 -700);
FORCEPROP 1 LAST OFFPAGE TRUE
J 0
(-1250 -825);
DISPLAY 0.872340 (-1250 -825);
PAINT GREEN (-1250 -825);
DISPLAY INVISIBLE (-1250 -825);
FORCEPROP 1 LAST COMMENT_BODY TRUE
J 0
(-1450 -800);
DISPLAY 0.872340 (-1450 -800);
PAINT GREEN (-1450 -800);
DISPLAY INVISIBLE (-1450 -800);
FORCEPROP 2 LAST PATH I1
J 0
(-1825 -650);
DISPLAY 0.680851 (-1825 -650);
DISPLAY INVISIBLE (-1825 -650);
FORCEADD UNIVERSAL_POWER..1
(-2200 975);
FORCEPROP 3 LASTPIN (-2200 925) SIG_NAME P3V3_E1S_0\g
J 0
(-2190 935);
DISPLAY 0.659574 (-2190 935);
PAINT MONO (-2190 935);
DISPLAY INVISIBLE (-2190 935);
FORCEPROP 1 LAST HDL_POWER P3V3_E1S_0
J 1
(-2200 1025);
DISPLAY 0.489362 (-2200 1025);
PAINT GREEN (-2200 1025);
FORCEPROP 2 LAST CDS_LIB pure_quanta_power
J 0
(-2200 975);
DISPLAY INVISIBLE (-2200 975);
FORCEPROP 2 LAST BOM_COST OCP3.0 
J 0
(-2200 1075);
DISPLAY 0.680851 (-2200 1075);
DISPLAY INVISIBLE (-2200 1075);
FORCEPROP 1 LAST PATH I100
J 0
(-2150 1000);
DISPLAY 0.872340 (-2150 1000);
PAINT AQUA (-2150 1000);
DISPLAY INVISIBLE (-2150 1000);
FORCEADD Q_RES..1
(-825 400);
FORCEPROP 1 LAST LOCATION R1038
J 0
(-875 450);
DISPLAY 0.489362 (-875 450);
PAINT SKYBLUE (-875 450);
FORCEPROP 2 LAST $SEC 1
J 0
(-875 600);
DISPLAY 0.680851 (-875 600);
PAINT MONO (-875 600);
DISPLAY INVISIBLE (-875 600);
FORCEPROP 2 LAST CDS_SEC 1
J 0
(-875 600);
DISPLAY 0.680851 (-875 600);
DISPLAY INVISIBLE (-875 600);
FORCEPROP 1 LASTPIN (-925 400) $PN 1
J 0
(-913 412);
DISPLAY 0.489362 (-913 412);
PAINT MONO (-913 412);
FORCEPROP 1 LASTPIN (-725 400) $PN 2
J 0
(-763 412);
DISPLAY 0.489362 (-763 412);
PAINT MONO (-763 412);
FORCEPROP 1 LAST VALUE 0
J 2
(-725 400);
DISPLAY 0.489362 (-725 400);
PAINT SKYBLUE (-725 400);
FORCEPROP 1 LAST MATERIAL CHIP
J 0
(-675 400);
DISPLAY 0.489362 (-675 400);
PAINT SKYBLUE (-675 400);
FORCEPROP 1 LAST PACK_TYPE 0402LF
J 0
(-750 350);
DISPLAY 0.489362 (-750 350);
PAINT SKYBLUE (-750 350);
DISPLAY INVISIBLE (-750 350);
FORCEPROP 1 LAST TOLERANCE 5%
J 0
(-825 350);
DISPLAY 0.489362 (-825 350);
PAINT SKYBLUE (-825 350);
DISPLAY INVISIBLE (-825 350);
FORCEPROP 1 LAST WATTAGE 1/16W
J 2
(-850 300);
DISPLAY 0.489362 (-850 300);
PAINT SKYBLUE (-850 300);
DISPLAY INVISIBLE (-850 300);
FORCEPROP 2 LAST BOM_COST OCP3.0 
J 0
(-750 500);
DISPLAY 0.680851 (-750 500);
DISPLAY INVISIBLE (-750 500);
FORCEPROP 2 LAST CDS_LIB pure_quanta
J 0
(-825 400);
DISPLAY INVISIBLE (-825 400);
FORCEPROP 1 LAST PATH I101
J 0
(-875 550);
DISPLAY 0.978723 (-875 550);
PAINT WHITE (-875 550);
DISPLAY INVISIBLE (-875 550);
FORCEPROP 1 LAST PART_NUMBER CS00002JB13
J 0
(-750 450);
DISPLAY 0.489362 (-750 450);
PAINT SKYBLUE (-750 450);
DISPLAY INVISIBLE (-750 450);
FORCEADD Q_RES..2
(-700 125);
FORCEPROP 1 LAST LOCATION R1000
J 0
(-655 250);
DISPLAY 0.489362 (-655 250);
PAINT SKYBLUE (-655 250);
FORCEPROP 2 LAST $SEC 1
J 0
(-650 350);
DISPLAY 0.680851 (-650 350);
PAINT MONO (-650 350);
DISPLAY INVISIBLE (-650 350);
FORCEPROP 2 LAST CDS_SEC 1
J 0
(-650 350);
DISPLAY 0.680851 (-650 350);
DISPLAY INVISIBLE (-650 350);
FORCEPROP 1 LASTPIN (-700 225) $PN 1
J 0
(-695 187);
DISPLAY 0.489362 (-695 187);
PAINT MONO (-695 187);
FORCEPROP 1 LASTPIN (-700 25) $PN 2
J 0
(-695 35);
DISPLAY 0.489362 (-695 35);
PAINT MONO (-695 35);
FORCEPROP 1 LAST TOLERANCE 5%
J 0
(-655 150);
DISPLAY 0.489362 (-655 150);
PAINT SKYBLUE (-655 150);
FORCEPROP 1 LAST MATERIAL CHIP
J 0
(-660 50);
DISPLAY 0.489362 (-660 50);
PAINT SKYBLUE (-660 50);
FORCEPROP 1 LAST VALUE 4.7K
J 0
(-655 200);
DISPLAY 0.489362 (-655 200);
PAINT SKYBLUE (-655 200);
FORCEPROP 1 LAST WATTAGE 1/16W
J 0
(-660 100);
DISPLAY 0.489362 (-660 100);
PAINT SKYBLUE (-660 100);
FORCEPROP 1 LAST PACK_TYPE 0402LF
J 0
(-660 -50);
DISPLAY 0.489362 (-660 -50);
PAINT SKYBLUE (-660 -50);
FORCEPROP 2 LAST CDS_LIB pure_quanta
J 0
(-700 125);
DISPLAY INVISIBLE (-700 125);
FORCEPROP 2 LAST BOM_COST OCP3.0 
J 0
(-650 300);
DISPLAY 0.680851 (-650 300);
DISPLAY INVISIBLE (-650 300);
FORCEPROP 1 LAST PATH I102
J 0
(-650 300);
DISPLAY 0.978723 (-650 300);
PAINT WHITE (-650 300);
DISPLAY INVISIBLE (-650 300);
FORCEPROP 1 LAST PART_NUMBER CS24702JB10
J 0
(-660 0);
DISPLAY 0.489362 (-660 0);
PAINT SKYBLUE (-660 0);
DISPLAY INVISIBLE (-660 0);
FORCEADD OFFPAGE..2
(200 400);
FORCEPROP 2 LAST $XR0 145 
J 0
(389 400);
DISPLAY 0.638298 (389 400);
PAINT MONO (389 400);
FORCEPROP 2 LAST CDS_LIB standard
J 0
(200 400);
DISPLAY INVISIBLE (200 400);
FORCEPROP 1 LAST OFFPAGE TRUE
J 0
(525 275);
DISPLAY 0.872340 (525 275);
PAINT GREEN (525 275);
DISPLAY INVISIBLE (525 275);
FORCEPROP 1 LAST COMMENT_BODY TRUE
J 0
(155 305);
DISPLAY 0.872340 (155 305);
PAINT GREEN (155 305);
DISPLAY INVISIBLE (155 305);
FORCEPROP 2 LAST PATH I103
J 0
(375 475);
DISPLAY 0.680851 (375 475);
DISPLAY INVISIBLE (375 475);
FORCEADD UNIVERSAL_POWER..1
(-1775 4625);
FORCEPROP 3 LASTPIN (-1775 4575) SIG_NAME P3V3_E1S_0\g
J 0
(-1765 4585);
DISPLAY 0.659574 (-1765 4585);
PAINT MONO (-1765 4585);
DISPLAY INVISIBLE (-1765 4585);
FORCEPROP 1 LAST HDL_POWER P3V3_E1S_0
J 1
(-1775 4675);
DISPLAY 0.872340 (-1775 4675);
PAINT GREEN (-1775 4675);
FORCEPROP 2 LAST CDS_LIB pure_quanta_power
J 0
(-1775 4625);
DISPLAY INVISIBLE (-1775 4625);
FORCEPROP 1 LAST PATH I104
J 0
(-1725 4650);
DISPLAY 0.872340 (-1725 4650);
PAINT AQUA (-1725 4650);
DISPLAY INVISIBLE (-1725 4650);
FORCEADD Q_RES..2
(2450 4475);
FORCEPROP 1 LAST LOCATION R1673
J 0
(2495 4600);
DISPLAY 0.638298 (2495 4600);
FORCEPROP 0 LAST $SEC 1
J 0
(2500 4650);
DISPLAY 0.680851 (2500 4650);
PAINT MONO (2500 4650);
DISPLAY INVISIBLE (2500 4650);
FORCEPROP 0 LAST CDS_SEC 1
J 0
(2500 4650);
DISPLAY 1.021277 (2500 4650);
DISPLAY INVISIBLE (2500 4650);
FORCEPROP 1 LASTPIN (2450 4575) $PN 1
J 0
(2455 4537);
DISPLAY 0.787234 (2455 4537);
PAINT MONO (2455 4537);
FORCEPROP 1 LASTPIN (2450 4375) $PN 2
J 0
(2455 4385);
DISPLAY 0.787234 (2455 4385);
PAINT MONO (2455 4385);
FORCEPROP 1 LAST VALUE 10K
J 0
(2495 4550);
DISPLAY 0.510638 (2495 4550);
FORCEPROP 1 LAST PACK_TYPE 0402LF
J 0
(2490 4350);
DISPLAY 0.510638 (2490 4350);
FORCEPROP 1 LAST WATTAGE 1/16W
J 0
(2490 4450);
DISPLAY 0.510638 (2490 4450);
FORCEPROP 1 LAST MATERIAL CHIP
J 0
(2490 4400);
DISPLAY 0.510638 (2490 4400);
FORCEPROP 1 LAST TOLERANCE 1%
J 0
(2495 4500);
DISPLAY 0.510638 (2495 4500);
FORCEPROP 2 LAST CDS_LIB pure_quanta
J 0
(2450 4475);
DISPLAY INVISIBLE (2450 4475);
FORCEPROP 1 LAST PATH I105
J 0
(2500 4650);
DISPLAY 0.978723 (2500 4650);
PAINT WHITE (2500 4650);
DISPLAY INVISIBLE (2500 4650);
FORCEPROP 1 LAST PART_NUMBER CS31002FB08
J 0
(2490 4300);
DISPLAY 0.510638 (2490 4300);
DISPLAY INVISIBLE (2490 4300);
FORCEADD Q_RES..2
(2925 -350);
FORCEPROP 1 LAST LOCATION R3773
J 0
(2970 -225);
DISPLAY 0.638298 (2970 -225);
FORCEPROP 0 LAST $SEC 1
J 0
(2975 -175);
DISPLAY 0.680851 (2975 -175);
PAINT MONO (2975 -175);
DISPLAY INVISIBLE (2975 -175);
FORCEPROP 0 LAST CDS_SEC 1
J 0
(2975 -175);
DISPLAY 0.680851 (2975 -175);
DISPLAY INVISIBLE (2975 -175);
FORCEPROP 1 LASTPIN (2925 -250) $PN 1
J 0
(2930 -288);
DISPLAY 0.787234 (2930 -288);
PAINT MONO (2930 -288);
FORCEPROP 1 LASTPIN (2925 -450) $PN 2
J 0
(2930 -440);
DISPLAY 0.787234 (2930 -440);
PAINT MONO (2930 -440);
FORCEPROP 1 LAST MATERIAL EMPTY
J 0
(2965 -425);
DISPLAY 0.638298 (2965 -425);
PAINT RED (2965 -425);
FORCEPROP 1 LAST WATTAGE 1/16W
J 0
(2965 -375);
DISPLAY 0.638298 (2965 -375);
FORCEPROP 1 LAST PACK_TYPE 0402LF
J 0
(2975 -475);
DISPLAY 0.638298 (2975 -475);
FORCEPROP 1 LAST TOLERANCE 5%
J 0
(2970 -325);
DISPLAY 0.638298 (2970 -325);
FORCEPROP 1 LAST VALUE 4.7K
J 0
(2970 -275);
DISPLAY 0.638298 (2970 -275);
FORCEPROP 2 LAST CDS_LIB pure_quanta
J 0
(2925 -350);
DISPLAY INVISIBLE (2925 -350);
FORCEPROP 1 LAST PATH I106
J 0
(2975 -175);
DISPLAY 0.978723 (2975 -175);
PAINT WHITE (2975 -175);
DISPLAY INVISIBLE (2975 -175);
FORCEPROP 1 LAST PART_NUMBER CS24702JB10
J 0
(2965 -475);
DISPLAY 0.638298 (2965 -475);
DISPLAY INVISIBLE (2965 -475);
FORCEADD UNIVERSAL_POWER..1
(2900 4800);
FORCEPROP 3 LASTPIN (2900 4750) SIG_NAME P3V3_E1S_0\g
J 0
(2910 4760);
DISPLAY 0.659574 (2910 4760);
PAINT MONO (2910 4760);
DISPLAY INVISIBLE (2910 4760);
FORCEPROP 1 LAST HDL_POWER P3V3_E1S_0
J 1
(2900 4850);
DISPLAY 0.872340 (2900 4850);
PAINT GREEN (2900 4850);
FORCEPROP 2 LAST CDS_LIB pure_quanta_power
J 0
(2900 4800);
DISPLAY INVISIBLE (2900 4800);
FORCEPROP 1 LAST PATH I107
J 0
(2950 4825);
DISPLAY 0.872340 (2950 4825);
PAINT AQUA (2950 4825);
DISPLAY INVISIBLE (2950 4825);
FORCEADD OFFPAGE..1
(-1525 3625);
FORCEPROP 2 LAST $XR0 67 
J 0
(-1776 3625);
DISPLAY 0.638298 (-1776 3625);
PAINT MONO (-1776 3625);
FORCEPROP 2 LAST CDS_LIB standard
J 0
(-1525 3625);
DISPLAY INVISIBLE (-1525 3625);
FORCEPROP 1 LAST OFFPAGE TRUE
J 0
(-1200 3500);
DISPLAY 0.872340 (-1200 3500);
PAINT GREEN (-1200 3500);
DISPLAY INVISIBLE (-1200 3500);
FORCEPROP 1 LAST COMMENT_BODY TRUE
J 0
(-1400 3525);
DISPLAY 0.872340 (-1400 3525);
PAINT GREEN (-1400 3525);
DISPLAY INVISIBLE (-1400 3525);
FORCEPROP 2 LAST PATH I14
J 0
(-1800 3675);
DISPLAY 0.680851 (-1800 3675);
DISPLAY INVISIBLE (-1800 3675);
FORCEADD OFFPAGE..1
(-1525 3675);
FORCEPROP 2 LAST $XR0 67 
J 0
(-1776 3675);
DISPLAY 0.638298 (-1776 3675);
PAINT MONO (-1776 3675);
FORCEPROP 2 LAST CDS_LIB standard
J 0
(-1525 3675);
DISPLAY INVISIBLE (-1525 3675);
FORCEPROP 1 LAST OFFPAGE TRUE
J 0
(-1200 3550);
DISPLAY 0.872340 (-1200 3550);
PAINT GREEN (-1200 3550);
DISPLAY INVISIBLE (-1200 3550);
FORCEPROP 1 LAST COMMENT_BODY TRUE
J 0
(-1400 3575);
DISPLAY 0.872340 (-1400 3575);
PAINT GREEN (-1400 3575);
DISPLAY INVISIBLE (-1400 3575);
FORCEPROP 2 LAST PATH I15
J 0
(-1800 3725);
DISPLAY 0.680851 (-1800 3725);
DISPLAY INVISIBLE (-1800 3725);
FORCEADD OFFPAGE..1
(-1525 3800);
FORCEPROP 2 LAST $XR0 28 
J 0
(-1776 3800);
DISPLAY 0.638298 (-1776 3800);
PAINT MONO (-1776 3800);
FORCEPROP 2 LAST CDS_LIB standard
J 0
(-1525 3800);
PAINT MONO (-1525 3800);
DISPLAY INVISIBLE (-1525 3800);
FORCEPROP 1 LAST OFFPAGE TRUE
J 0
(-1200 3675);
DISPLAY 0.872340 (-1200 3675);
PAINT GREEN (-1200 3675);
DISPLAY INVISIBLE (-1200 3675);
FORCEPROP 1 LAST COMMENT_BODY TRUE
J 0
(-1400 3700);
DISPLAY 0.872340 (-1400 3700);
PAINT GREEN (-1400 3700);
DISPLAY INVISIBLE (-1400 3700);
FORCEPROP 2 LAST PATH I16
J 0
(-1800 3850);
DISPLAY 0.680851 (-1800 3850);
DISPLAY INVISIBLE (-1800 3850);
FORCEADD OFFPAGE..1
(-1525 3750);
FORCEPROP 2 LAST $XR0 28 
J 0
(-1776 3750);
DISPLAY 0.638298 (-1776 3750);
PAINT MONO (-1776 3750);
FORCEPROP 2 LAST CDS_LIB standard
J 0
(-1525 3750);
PAINT MONO (-1525 3750);
DISPLAY INVISIBLE (-1525 3750);
FORCEPROP 1 LAST OFFPAGE TRUE
J 0
(-1200 3625);
DISPLAY 0.872340 (-1200 3625);
PAINT GREEN (-1200 3625);
DISPLAY INVISIBLE (-1200 3625);
FORCEPROP 1 LAST COMMENT_BODY TRUE
J 0
(-1400 3650);
DISPLAY 0.872340 (-1400 3650);
PAINT GREEN (-1400 3650);
DISPLAY INVISIBLE (-1400 3650);
FORCEPROP 2 LAST PATH I17
J 0
(-1800 3800);
DISPLAY 0.680851 (-1800 3800);
DISPLAY INVISIBLE (-1800 3800);
FORCEADD OFFPAGE..1
(-1525 3950);
FORCEPROP 2 LAST $XR0 145 
J 0
(-1777 3950);
DISPLAY 0.638298 (-1777 3950);
PAINT MONO (-1777 3950);
FORCEPROP 2 LAST CDS_LIB standard
J 0
(-1525 3950);
PAINT MONO (-1525 3950);
DISPLAY INVISIBLE (-1525 3950);
FORCEPROP 1 LAST OFFPAGE TRUE
J 0
(-1200 3825);
DISPLAY 0.872340 (-1200 3825);
PAINT GREEN (-1200 3825);
DISPLAY INVISIBLE (-1200 3825);
FORCEPROP 1 LAST COMMENT_BODY TRUE
J 0
(-1400 3850);
DISPLAY 0.872340 (-1400 3850);
PAINT GREEN (-1400 3850);
DISPLAY INVISIBLE (-1400 3850);
FORCEPROP 2 LAST PATH I18
J 0
(-1800 4000);
DISPLAY 0.680851 (-1800 4000);
DISPLAY INVISIBLE (-1800 4000);
FORCEADD Q_RES..1
(-850 -700);
FORCEPROP 1 LAST LOCATION R3775
J 0
(-900 -650);
DISPLAY 0.978723 (-900 -650);
FORCEPROP 0 LAST $SEC 1
J 0
(-900 -600);
DISPLAY 0.680851 (-900 -600);
PAINT MONO (-900 -600);
DISPLAY INVISIBLE (-900 -600);
FORCEPROP 0 LAST CDS_SEC 1
J 0
(-900 -600);
DISPLAY 1.021277 (-900 -600);
DISPLAY INVISIBLE (-900 -600);
FORCEPROP 1 LASTPIN (-950 -700) $PN 1
J 0
(-938 -688);
DISPLAY 0.787234 (-938 -688);
PAINT MONO (-938 -688);
FORCEPROP 1 LASTPIN (-750 -700) $PN 2
J 0
(-788 -688);
DISPLAY 0.787234 (-788 -688);
PAINT MONO (-788 -688);
FORCEPROP 1 LAST MATERIAL CHIP
J 0
(-600 -700);
DISPLAY 0.510638 (-600 -700);
FORCEPROP 1 LAST TOLERANCE 5%
J 0
(-675 -700);
DISPLAY 0.510638 (-675 -700);
FORCEPROP 1 LAST VALUE 0
J 2
(-700 -700);
DISPLAY 0.510638 (-700 -700);
FORCEPROP 2 LAST CDS_LIB pure_quanta
J 0
(-850 -700);
DISPLAY INVISIBLE (-850 -700);
FORCEPROP 1 LAST PACK_TYPE 0402LF
J 0
(-950 -625);
DISPLAY 0.404255 (-950 -625);
DISPLAY INVISIBLE (-950 -625);
FORCEPROP 1 LAST WATTAGE 1/16W
J 2
(-725 -625);
DISPLAY 0.404255 (-725 -625);
DISPLAY INVISIBLE (-725 -625);
FORCEPROP 1 LAST PATH I2
J 0
(-900 -550);
DISPLAY 0.978723 (-900 -550);
PAINT WHITE (-900 -550);
DISPLAY INVISIBLE (-900 -550);
FORCEPROP 1 LAST PART_NUMBER CS00002JB13
J 0
(-950 -650);
DISPLAY 0.404255 (-950 -650);
DISPLAY INVISIBLE (-950 -650);
FORCEADD UNIVERSAL_GND..1
(-250 2800);
FORCEPROP 3 LASTPIN (-250 2850) SIG_NAME GND\g
J 0
(-240 2860);
DISPLAY 0.659574 (-240 2860);
PAINT MONO (-240 2860);
DISPLAY INVISIBLE (-240 2860);
FORCEPROP 2 LAST ROOM IO_SLOT
J 1
(-475 2875);
DISPLAY 0.744681 (-475 2875);
FORCEPROP 2 LAST CDS_LIB pure_quanta_power
J 0
(-250 2800);
DISPLAY INVISIBLE (-250 2800);
FORCEPROP 1 LAST HDL_POWER GND
J 1
(-225 2725);
DISPLAY 0.872340 (-225 2725);
PAINT GREEN (-225 2725);
DISPLAY INVISIBLE (-225 2725);
FORCEPROP 1 LAST PATH I20
J 0
(-175 2800);
DISPLAY 0.872340 (-175 2800);
PAINT AQUA (-175 2800);
DISPLAY INVISIBLE (-175 2800);
FORCEADD TAP..1
R 2
(-625 3200);
FORCEPROP 3 LASTPIN (-575 3200) SIG_NAME P3E_CPU0_P4_TX_C_DN<3>
J 0
(-565 3210);
DISPLAY 0.659574 (-565 3210);
PAINT MONO (-565 3210);
DISPLAY INVISIBLE (-565 3210);
FORCEPROP 1 LASTPIN (-575 3200) BN 3
J 2
(-563 3208);
DISPLAY 0.680851 (-563 3208);
PAINT GREEN (-563 3208);
FORCEPROP 2 LAST CDS_LIB standard
J 0
(-625 3200);
PAINT MONO (-625 3200);
DISPLAY INVISIBLE (-625 3200);
FORCEPROP 1 LAST BODY_TYPE PLUMBING
J 2
(-625 3250);
DISPLAY 0.872340 (-625 3250);
PAINT GREEN (-625 3250);
DISPLAY INVISIBLE (-625 3250);
FORCEPROP 1 LAST HDL_TAP TRUE
J 2
(-950 3075);
DISPLAY 0.872340 (-950 3075);
PAINT GREEN (-950 3075);
DISPLAY INVISIBLE (-950 3075);
FORCEPROP 1 LAST PATH I21
J 2
(-623 3200);
DISPLAY 0.872340 (-623 3200);
PAINT GREEN (-623 3200);
DISPLAY INVISIBLE (-623 3200);
FORCEADD TAP..1
R 2
(-625 3300);
FORCEPROP 3 LASTPIN (-575 3300) SIG_NAME P3E_CPU0_P4_TX_C_DN<2>
J 0
(-565 3310);
DISPLAY 0.659574 (-565 3310);
PAINT MONO (-565 3310);
DISPLAY INVISIBLE (-565 3310);
FORCEPROP 1 LASTPIN (-575 3300) BN 2
J 2
(-563 3308);
DISPLAY 0.680851 (-563 3308);
PAINT GREEN (-563 3308);
FORCEPROP 2 LAST CDS_LIB standard
J 0
(-625 3300);
PAINT MONO (-625 3300);
DISPLAY INVISIBLE (-625 3300);
FORCEPROP 1 LAST BODY_TYPE PLUMBING
J 2
(-625 3350);
DISPLAY 0.872340 (-625 3350);
PAINT GREEN (-625 3350);
DISPLAY INVISIBLE (-625 3350);
FORCEPROP 1 LAST HDL_TAP TRUE
J 2
(-950 3175);
DISPLAY 0.872340 (-950 3175);
PAINT GREEN (-950 3175);
DISPLAY INVISIBLE (-950 3175);
FORCEPROP 1 LAST PATH I22
J 2
(-623 3300);
DISPLAY 0.872340 (-623 3300);
PAINT GREEN (-623 3300);
DISPLAY INVISIBLE (-623 3300);
FORCEADD TAP..1
R 2
(-475 3150);
FORCEPROP 3 LASTPIN (-425 3150) SIG_NAME P3E_CPU0_P4_TX_C_DP<3>
J 0
(-415 3160);
DISPLAY 0.659574 (-415 3160);
PAINT MONO (-415 3160);
DISPLAY INVISIBLE (-415 3160);
FORCEPROP 1 LASTPIN (-425 3150) BN 3
J 2
(-413 3158);
DISPLAY 0.680851 (-413 3158);
PAINT GREEN (-413 3158);
FORCEPROP 2 LAST CDS_LIB standard
J 0
(-475 3150);
PAINT MONO (-475 3150);
DISPLAY INVISIBLE (-475 3150);
FORCEPROP 1 LAST BODY_TYPE PLUMBING
J 2
(-475 3200);
DISPLAY 0.872340 (-475 3200);
PAINT GREEN (-475 3200);
DISPLAY INVISIBLE (-475 3200);
FORCEPROP 1 LAST HDL_TAP TRUE
J 2
(-800 3025);
DISPLAY 0.872340 (-800 3025);
PAINT GREEN (-800 3025);
DISPLAY INVISIBLE (-800 3025);
FORCEPROP 1 LAST PATH I23
J 2
(-473 3150);
DISPLAY 0.872340 (-473 3150);
PAINT GREEN (-473 3150);
DISPLAY INVISIBLE (-473 3150);
FORCEADD TAP..1
R 2
(-475 3350);
FORCEPROP 3 LASTPIN (-425 3350) SIG_NAME P3E_CPU0_P4_TX_C_DP<2>
J 0
(-415 3360);
DISPLAY 0.659574 (-415 3360);
PAINT MONO (-415 3360);
DISPLAY INVISIBLE (-415 3360);
FORCEPROP 1 LASTPIN (-425 3350) BN 2
J 2
(-413 3358);
DISPLAY 0.680851 (-413 3358);
PAINT GREEN (-413 3358);
FORCEPROP 2 LAST CDS_LIB standard
J 0
(-475 3350);
PAINT MONO (-475 3350);
DISPLAY INVISIBLE (-475 3350);
FORCEPROP 1 LAST BODY_TYPE PLUMBING
J 2
(-475 3400);
DISPLAY 0.872340 (-475 3400);
PAINT GREEN (-475 3400);
DISPLAY INVISIBLE (-475 3400);
FORCEPROP 1 LAST HDL_TAP TRUE
J 2
(-800 3225);
DISPLAY 0.872340 (-800 3225);
PAINT GREEN (-800 3225);
DISPLAY INVISIBLE (-800 3225);
FORCEPROP 1 LAST PATH I24
J 2
(-473 3350);
DISPLAY 0.872340 (-473 3350);
PAINT GREEN (-473 3350);
DISPLAY INVISIBLE (-473 3350);
FORCEADD TAP..1
R 2
(-625 3450);
FORCEPROP 3 LASTPIN (-575 3450) SIG_NAME P3E_CPU0_P4_TX_C_DN<1>
J 0
(-565 3460);
DISPLAY 0.659574 (-565 3460);
PAINT MONO (-565 3460);
DISPLAY INVISIBLE (-565 3460);
FORCEPROP 1 LASTPIN (-575 3450) BN 1
J 2
(-563 3458);
DISPLAY 0.680851 (-563 3458);
PAINT GREEN (-563 3458);
FORCEPROP 2 LAST CDS_LIB standard
J 0
(-625 3450);
PAINT MONO (-625 3450);
DISPLAY INVISIBLE (-625 3450);
FORCEPROP 1 LAST BODY_TYPE PLUMBING
J 2
(-625 3500);
DISPLAY 0.872340 (-625 3500);
PAINT GREEN (-625 3500);
DISPLAY INVISIBLE (-625 3500);
FORCEPROP 1 LAST HDL_TAP TRUE
J 2
(-950 3325);
DISPLAY 0.872340 (-950 3325);
PAINT GREEN (-950 3325);
DISPLAY INVISIBLE (-950 3325);
FORCEPROP 1 LAST PATH I25
J 2
(-623 3450);
DISPLAY 0.872340 (-623 3450);
PAINT GREEN (-623 3450);
DISPLAY INVISIBLE (-623 3450);
FORCEADD TAP..1
R 2
(-625 3600);
FORCEPROP 3 LASTPIN (-575 3600) SIG_NAME P3E_CPU0_P4_TX_C_DN<0>
J 0
(-565 3610);
DISPLAY 0.659574 (-565 3610);
PAINT MONO (-565 3610);
DISPLAY INVISIBLE (-565 3610);
FORCEPROP 1 LASTPIN (-575 3600) BN 0
J 2
(-563 3608);
DISPLAY 0.680851 (-563 3608);
PAINT GREEN (-563 3608);
FORCEPROP 2 LAST CDS_LIB standard
J 0
(-625 3600);
DISPLAY INVISIBLE (-625 3600);
FORCEPROP 1 LAST BODY_TYPE PLUMBING
J 2
(-625 3650);
DISPLAY 0.872340 (-625 3650);
PAINT GREEN (-625 3650);
DISPLAY INVISIBLE (-625 3650);
FORCEPROP 1 LAST HDL_TAP TRUE
J 2
(-950 3475);
DISPLAY 0.872340 (-950 3475);
PAINT GREEN (-950 3475);
DISPLAY INVISIBLE (-950 3475);
FORCEPROP 1 LAST PATH I26
J 2
(-623 3600);
DISPLAY 0.872340 (-623 3600);
PAINT GREEN (-623 3600);
DISPLAY INVISIBLE (-623 3600);
FORCEADD TAP..1
R 2
(-475 3500);
FORCEPROP 3 LASTPIN (-425 3500) SIG_NAME P3E_CPU0_P4_TX_C_DP<1>
J 0
(-415 3510);
DISPLAY 0.659574 (-415 3510);
PAINT MONO (-415 3510);
DISPLAY INVISIBLE (-415 3510);
FORCEPROP 1 LASTPIN (-425 3500) BN 1
J 2
(-413 3508);
DISPLAY 0.680851 (-413 3508);
PAINT GREEN (-413 3508);
FORCEPROP 2 LAST CDS_LIB standard
J 0
(-475 3500);
PAINT MONO (-475 3500);
DISPLAY INVISIBLE (-475 3500);
FORCEPROP 1 LAST BODY_TYPE PLUMBING
J 2
(-475 3550);
DISPLAY 0.872340 (-475 3550);
PAINT GREEN (-475 3550);
DISPLAY INVISIBLE (-475 3550);
FORCEPROP 1 LAST HDL_TAP TRUE
J 2
(-800 3375);
DISPLAY 0.872340 (-800 3375);
PAINT GREEN (-800 3375);
DISPLAY INVISIBLE (-800 3375);
FORCEPROP 1 LAST PATH I27
J 2
(-473 3500);
DISPLAY 0.872340 (-473 3500);
PAINT GREEN (-473 3500);
DISPLAY INVISIBLE (-473 3500);
FORCEADD TAP..1
R 2
(-475 3650);
FORCEPROP 3 LASTPIN (-425 3650) SIG_NAME P3E_CPU0_P4_TX_C_DP<0>
J 0
(-415 3660);
DISPLAY 0.659574 (-415 3660);
PAINT MONO (-415 3660);
DISPLAY INVISIBLE (-415 3660);
FORCEPROP 1 LASTPIN (-425 3650) BN 0
J 2
(-413 3658);
DISPLAY 0.680851 (-413 3658);
PAINT GREEN (-413 3658);
FORCEPROP 2 LAST CDS_LIB standard
J 0
(-475 3650);
DISPLAY INVISIBLE (-475 3650);
FORCEPROP 1 LAST BODY_TYPE PLUMBING
J 2
(-475 3700);
DISPLAY 0.872340 (-475 3700);
PAINT GREEN (-475 3700);
DISPLAY INVISIBLE (-475 3700);
FORCEPROP 1 LAST HDL_TAP TRUE
J 2
(-800 3525);
DISPLAY 0.872340 (-800 3525);
PAINT GREEN (-800 3525);
DISPLAY INVISIBLE (-800 3525);
FORCEPROP 1 LAST PATH I28
J 2
(-473 3650);
DISPLAY 0.872340 (-473 3650);
PAINT GREEN (-473 3650);
DISPLAY INVISIBLE (-473 3650);
FORCEADD OFFPAGE..1
(-3000 4050);
FORCEPROP 2 LAST $XR1 83 
J 0
(-3341 4050);
DISPLAY 0.638298 (-3341 4050);
PAINT MONO (-3341 4050);
FORCEPROP 2 LAST $XR0 81 
J 0
(-3251 4050);
DISPLAY 0.638298 (-3251 4050);
PAINT MONO (-3251 4050);
FORCEPROP 2 LAST CDS_LIB standard
J 0
(-3000 4050);
PAINT MONO (-3000 4050);
DISPLAY INVISIBLE (-3000 4050);
FORCEPROP 1 LAST OFFPAGE TRUE
J 0
(-2675 3925);
DISPLAY 0.872340 (-2675 3925);
PAINT GREEN (-2675 3925);
DISPLAY INVISIBLE (-2675 3925);
FORCEPROP 1 LAST COMMENT_BODY TRUE
J 0
(-2875 3950);
DISPLAY 0.872340 (-2875 3950);
PAINT GREEN (-2875 3950);
DISPLAY INVISIBLE (-2875 3950);
FORCEPROP 2 LAST PATH I29
J 0
(-3250 4100);
DISPLAY 0.680851 (-3250 4100);
DISPLAY INVISIBLE (-3250 4100);
FORCEADD UNIVERSAL_GND..1
(-25 -975);
FORCEPROP 3 LASTPIN (-25 -925) SIG_NAME GND\g
J 0
(-15 -915);
DISPLAY 0.659574 (-15 -915);
PAINT MONO (-15 -915);
DISPLAY INVISIBLE (-15 -915);
FORCEPROP 2 LAST CDS_LIB pure_quanta_power
J 0
(-25 -975);
DISPLAY INVISIBLE (-25 -975);
FORCEPROP 1 LAST HDL_POWER GND
J 1
(0 -1050);
DISPLAY 0.872340 (0 -1050);
PAINT GREEN (0 -1050);
DISPLAY INVISIBLE (0 -1050);
FORCEPROP 1 LAST PATH I3
J 0
(50 -975);
DISPLAY 0.872340 (50 -975);
PAINT AQUA (50 -975);
DISPLAY INVISIBLE (50 -975);
FORCEADD Q_RES..1
(-1850 4050);
FORCEPROP 1 LAST LOCATION R3779
J 0
(-2000 4050);
DISPLAY 0.638298 (-2000 4050);
FORCEPROP 0 LAST $SEC 1
J 0
(-1775 4150);
DISPLAY 0.680851 (-1775 4150);
PAINT MONO (-1775 4150);
DISPLAY INVISIBLE (-1775 4150);
FORCEPROP 0 LAST CDS_SEC 1
J 0
(-1775 4150);
DISPLAY 1.021277 (-1775 4150);
DISPLAY INVISIBLE (-1775 4150);
FORCEPROP 1 LASTPIN (-1950 4050) $PN 1
J 0
(-1938 4062);
DISPLAY 0.787234 (-1938 4062);
PAINT MONO (-1938 4062);
FORCEPROP 1 LASTPIN (-1750 4050) $PN 2
J 0
(-1788 4062);
DISPLAY 0.787234 (-1788 4062);
PAINT MONO (-1788 4062);
FORCEPROP 1 LAST VALUE 0
J 2
(-1675 4050);
DISPLAY 0.638298 (-1675 4050);
FORCEPROP 1 LAST MATERIAL CHIP
J 0
(-1575 4050);
DISPLAY 0.638298 (-1575 4050);
FORCEPROP 1 LAST PACK_TYPE 0402LF
J 0
(-1950 4125);
DISPLAY 0.319149 (-1950 4125);
FORCEPROP 1 LAST WATTAGE 1/16W
J 2
(-1775 4125);
DISPLAY 0.319149 (-1775 4125);
FORCEPROP 1 LAST TOLERANCE 5%
J 0
(-1650 4050);
DISPLAY 0.638298 (-1650 4050);
FORCEPROP 2 LAST CDS_LIB pure_quanta
J 0
(-1850 4050);
DISPLAY INVISIBLE (-1850 4050);
FORCEPROP 1 LAST PATH I30
J 0
(-1900 4200);
DISPLAY 0.978723 (-1900 4200);
PAINT WHITE (-1900 4200);
DISPLAY INVISIBLE (-1900 4200);
FORCEPROP 1 LAST PART_NUMBER CS00002JB13
J 0
(-1950 4100);
DISPLAY 0.319149 (-1950 4100);
DISPLAY INVISIBLE (-1950 4100);
FORCEADD Q_RES..2
(-1775 4375);
FORCEPROP 1 LAST LOCATION R2317
J 0
(-1730 4500);
DISPLAY 0.723404 (-1730 4500);
PAINT AQUA (-1730 4500);
FORCEPROP 0 LAST $SEC 1
J 0
(-1725 4550);
DISPLAY 0.680851 (-1725 4550);
PAINT MONO (-1725 4550);
DISPLAY INVISIBLE (-1725 4550);
FORCEPROP 0 LAST CDS_SEC 1
J 0
(-1725 4550);
DISPLAY 1.021277 (-1725 4550);
DISPLAY INVISIBLE (-1725 4550);
FORCEPROP 1 LASTPIN (-1775 4475) $PN 1
J 0
(-1770 4437);
DISPLAY 0.787234 (-1770 4437);
PAINT MONO (-1770 4437);
FORCEPROP 1 LASTPIN (-1775 4275) $PN 2
J 0
(-1770 4285);
DISPLAY 0.787234 (-1770 4285);
PAINT MONO (-1770 4285);
FORCEPROP 1 LAST MATERIAL CHIP
J 0
(-1735 4300);
DISPLAY 0.723404 (-1735 4300);
PAINT SKYBLUE (-1735 4300);
FORCEPROP 1 LAST VALUE 10K
J 0
(-1730 4450);
DISPLAY 0.723404 (-1730 4450);
PAINT SKYBLUE (-1730 4450);
FORCEPROP 1 LAST TOLERANCE 1%
J 0
(-1730 4400);
DISPLAY 0.723404 (-1730 4400);
PAINT SKYBLUE (-1730 4400);
FORCEPROP 1 LAST WATTAGE 1/16W
J 0
(-1735 4350);
DISPLAY 0.723404 (-1735 4350);
PAINT SKYBLUE (-1735 4350);
FORCEPROP 1 LAST PACK_TYPE 0402LF
J 0
(-1725 4225);
DISPLAY 0.723404 (-1725 4225);
PAINT SKYBLUE (-1725 4225);
FORCEPROP 2 LAST CDS_LIB pure_quanta
J 0
(-1775 4375);
DISPLAY INVISIBLE (-1775 4375);
FORCEPROP 1 LAST PATH I31
J 0
(-1725 4550);
DISPLAY 0.978723 (-1725 4550);
PAINT WHITE (-1725 4550);
DISPLAY INVISIBLE (-1725 4550);
FORCEPROP 1 LAST PART_NUMBER CS31002FB08
J 0
(-1735 4250);
DISPLAY 0.723404 (-1735 4250);
PAINT WHITE (-1735 4250);
DISPLAY INVISIBLE (-1735 4250);
FORCEADD UNIVERSAL_POWER..1
(-500 4850);
FORCEPROP 3 LASTPIN (-500 4800) SIG_NAME P3V3_E1S_0\g
J 0
(-490 4810);
DISPLAY 0.659574 (-490 4810);
PAINT MONO (-490 4810);
DISPLAY INVISIBLE (-490 4810);
FORCEPROP 1 LAST HDL_POWER P3V3_E1S_0
J 1
(-500 4900);
DISPLAY 0.872340 (-500 4900);
PAINT GREEN (-500 4900);
FORCEPROP 2 LAST CDS_LIB pure_quanta_power
J 0
(-500 4850);
DISPLAY INVISIBLE (-500 4850);
FORCEPROP 1 LAST PATH I33
J 0
(-450 4875);
DISPLAY 0.872340 (-450 4875);
PAINT AQUA (-450 4875);
DISPLAY INVISIBLE (-450 4875);
FORCEADD UNIVERSAL_POWER..1
(-200 5025);
FORCEPROP 3 LASTPIN (-200 4975) SIG_NAME P12V_E1S_0_R\g
J 0
(-190 4985);
DISPLAY 0.659574 (-190 4985);
PAINT MONO (-190 4985);
DISPLAY INVISIBLE (-190 4985);
FORCEPROP 1 LAST HDL_POWER P12V_E1S_0_R
J 1
(-200 5075);
DISPLAY 0.872340 (-200 5075);
PAINT GREEN (-200 5075);
FORCEPROP 2 LAST CDS_LIB pure_quanta_power
J 0
(-200 5025);
DISPLAY INVISIBLE (-200 5025);
FORCEPROP 1 LAST PATH I34
J 0
(-150 5050);
DISPLAY 0.872340 (-150 5050);
PAINT AQUA (-150 5050);
DISPLAY INVISIBLE (-150 5050);
FORCEADD UNIVERSAL_GND..1
(1100 -575);
FORCEPROP 3 LASTPIN (1100 -525) SIG_NAME GND\g
J 0
(1110 -515);
DISPLAY 0.659574 (1110 -515);
PAINT MONO (1110 -515);
DISPLAY INVISIBLE (1110 -515);
FORCEPROP 2 LAST CDS_LIB pure_quanta_power
J 0
(1100 -575);
DISPLAY INVISIBLE (1100 -575);
FORCEPROP 1 LAST HDL_POWER GND
J 1
(1125 -650);
DISPLAY 0.872340 (1125 -650);
PAINT GREEN (1125 -650);
DISPLAY INVISIBLE (1125 -650);
FORCEPROP 1 LAST PATH I35
J 0
(1175 -575);
DISPLAY 0.872340 (1175 -575);
PAINT AQUA (1175 -575);
DISPLAY INVISIBLE (1175 -575);
FORCEADD Q_CAP..1
(1100 -350);
FORCEPROP 1 LAST LOCATION C1592
J 0
(1150 -250);
DISPLAY 0.978723 (1150 -250);
FORCEPROP 0 LAST $SEC 1
J 0
(1150 -200);
DISPLAY 0.680851 (1150 -200);
PAINT MONO (1150 -200);
DISPLAY INVISIBLE (1150 -200);
FORCEPROP 0 LAST CDS_SEC 1
J 0
(1150 -200);
DISPLAY 1.021277 (1150 -200);
DISPLAY INVISIBLE (1150 -200);
FORCEPROP 1 LASTPIN (1100 -250) $PN 1
J 0
(1110 -270);
DISPLAY 0.787234 (1110 -270);
PAINT MONO (1110 -270);
FORCEPROP 1 LASTPIN (1100 -450) $PN 2
J 0
(1110 -470);
DISPLAY 0.787234 (1110 -470);
PAINT MONO (1110 -470);
FORCEPROP 1 LAST TOLERANCE 10%
J 0
(1150 -400);
DISPLAY 0.510638 (1150 -400);
FORCEPROP 1 LAST VOLTAGE 25V
J 0
(1150 -350);
DISPLAY 0.510638 (1150 -350);
FORCEPROP 1 LAST VALUE 0.1UF
J 0
(1150 -300);
DISPLAY 0.510638 (1150 -300);
FORCEPROP 1 LAST MATERIAL X7R
J 0
(1150 -450);
DISPLAY 0.510638 (1150 -450);
FORCEPROP 1 LAST PACK_TYPE 0402
J 0
(1150 -550);
DISPLAY 0.510638 (1150 -550);
FORCEPROP 2 LAST CDS_LIB pure_quanta
J 2
(1100 -350);
DISPLAY INVISIBLE (1100 -350);
FORCEPROP 1 LAST PATH I36
J 0
(1150 -200);
DISPLAY 0.978723 (1150 -200);
PAINT WHITE (1150 -200);
DISPLAY INVISIBLE (1150 -200);
FORCEPROP 1 LAST PART_NUMBER CH4104K1B00
J 0
(1150 -500);
DISPLAY 0.510638 (1150 -500);
DISPLAY INVISIBLE (1150 -500);
FORCEADD Q_RES..1
(1900 -800);
FORCEPROP 1 LAST LOCATION R2114
J 0
(1675 -800);
DISPLAY 0.638298 (1675 -800);
FORCEPROP 0 LAST $SEC 1
J 0
(1675 -750);
DISPLAY 0.680851 (1675 -750);
PAINT MONO (1675 -750);
DISPLAY INVISIBLE (1675 -750);
FORCEPROP 0 LAST CDS_SEC 1
J 0
(1675 -750);
DISPLAY 1.021277 (1675 -750);
DISPLAY INVISIBLE (1675 -750);
FORCEPROP 1 LASTPIN (1800 -800) $PN 1
J 0
(1812 -788);
DISPLAY 0.787234 (1812 -788);
PAINT MONO (1812 -788);
FORCEPROP 1 LASTPIN (2000 -800) $PN 2
J 0
(1962 -788);
DISPLAY 0.787234 (1962 -788);
PAINT MONO (1962 -788);
FORCEPROP 1 LAST VALUE 0
J 2
(2050 -800);
DISPLAY 0.510638 (2050 -800);
FORCEPROP 1 LAST TOLERANCE 5%
J 0
(2075 -800);
DISPLAY 0.510638 (2075 -800);
FORCEPROP 1 LAST MATERIAL CHIP
J 0
(2150 -800);
DISPLAY 0.510638 (2150 -800);
FORCEPROP 1 LAST WATTAGE 1/16W
J 2
(2025 -725);
DISPLAY 0.404255 (2025 -725);
DISPLAY INVISIBLE (2025 -725);
FORCEPROP 1 LAST PACK_TYPE 0402LF
J 0
(1800 -725);
DISPLAY 0.404255 (1800 -725);
DISPLAY INVISIBLE (1800 -725);
FORCEPROP 2 LAST CDS_LIB pure_quanta
J 0
(1900 -800);
DISPLAY INVISIBLE (1900 -800);
FORCEPROP 1 LAST PATH I37
J 0
(1850 -650);
DISPLAY 0.978723 (1850 -650);
PAINT WHITE (1850 -650);
DISPLAY INVISIBLE (1850 -650);
FORCEPROP 1 LAST PART_NUMBER CS00002JB13
J 0
(1800 -750);
DISPLAY 0.404255 (1800 -750);
DISPLAY INVISIBLE (1800 -750);
FORCEADD Q_RES..1
(1900 -700);
FORCEPROP 1 LAST LOCATION R3772
J 0
(1675 -700);
DISPLAY 0.638298 (1675 -700);
FORCEPROP 0 LAST $SEC 1
J 0
(2025 -600);
DISPLAY 0.680851 (2025 -600);
PAINT MONO (2025 -600);
DISPLAY INVISIBLE (2025 -600);
FORCEPROP 0 LAST CDS_SEC 1
J 0
(2025 -600);
DISPLAY 1.021277 (2025 -600);
DISPLAY INVISIBLE (2025 -600);
FORCEPROP 1 LASTPIN (1800 -700) $PN 1
J 0
(1812 -688);
DISPLAY 0.787234 (1812 -688);
PAINT MONO (1812 -688);
FORCEPROP 1 LASTPIN (2000 -700) $PN 2
J 0
(1962 -688);
DISPLAY 0.787234 (1962 -688);
PAINT MONO (1962 -688);
FORCEPROP 1 LAST PACK_TYPE 0402LF
J 0
(1800 -625);
DISPLAY 0.404255 (1800 -625);
FORCEPROP 1 LAST VALUE 0
J 2
(2050 -700);
DISPLAY 0.510638 (2050 -700);
FORCEPROP 1 LAST TOLERANCE 5%
J 0
(2075 -700);
DISPLAY 0.510638 (2075 -700);
FORCEPROP 1 LAST MATERIAL CHIP
J 0
(2150 -700);
DISPLAY 0.510638 (2150 -700);
FORCEPROP 1 LAST WATTAGE 1/16W
J 2
(2025 -625);
DISPLAY 0.404255 (2025 -625);
FORCEPROP 2 LAST CDS_LIB pure_quanta
J 0
(1900 -700);
DISPLAY INVISIBLE (1900 -700);
FORCEPROP 1 LAST PATH I38
J 0
(1850 -550);
DISPLAY 0.978723 (1850 -550);
PAINT WHITE (1850 -550);
DISPLAY INVISIBLE (1850 -550);
FORCEPROP 1 LAST PART_NUMBER CS00002JB13
J 0
(1800 -650);
DISPLAY 0.404255 (1800 -650);
DISPLAY INVISIBLE (1800 -650);
FORCEADD 74LVC2G07DW7..1
(400 -750);
FORCEPROP 1 LAST LOCATION U134
J 0
(231 -369);
DISPLAY 0.723404 (231 -369);
PAINT GREEN (231 -369);
FORCEPROP 0 LAST $SEC 1
J 0
(250 -225);
DISPLAY 0.680851 (250 -225);
PAINT MONO (250 -225);
DISPLAY INVISIBLE (250 -225);
FORCEPROP 0 LAST CDS_SEC 1
J 0
(250 -225);
DISPLAY 1.021277 (250 -225);
DISPLAY INVISIBLE (250 -225);
FORCEPROP 0 LASTPIN (75 -700) $PN 1
J 2
(65 -690);
DISPLAY 0.680851 (65 -690);
PAINT MONO (65 -690);
FORCEPROP 0 LASTPIN (725 -700) $PN 6
J 0
(735 -690);
DISPLAY 0.680851 (735 -690);
PAINT MONO (735 -690);
FORCEPROP 0 LASTPIN (75 -800) $PN 3
J 2
(65 -790);
DISPLAY 0.680851 (65 -790);
PAINT MONO (65 -790);
FORCEPROP 0 LASTPIN (725 -800) $PN 4
J 0
(735 -790);
DISPLAY 0.680851 (735 -790);
PAINT MONO (735 -790);
FORCEPROP 0 LASTPIN (75 -750) $PN 2
J 2
(65 -740);
DISPLAY 0.680851 (65 -740);
PAINT MONO (65 -740);
FORCEPROP 0 LASTPIN (725 -750) $PN 5
J 0
(735 -740);
DISPLAY 0.680851 (735 -740);
PAINT MONO (735 -740);
FORCEPROP 2 LAST VALUE 74LVC2G07DW-7
J 0
(250 -325);
DISPLAY 1.021277 (250 -325);
FORCEPROP 1 LAST MATERIAL IC
J 0
(231 -643);
DISPLAY 0.723404 (231 -643);
PAINT GREEN (231 -643);
FORCEPROP 2 LAST PART_TYPE SMLF
J 0
(250 -275);
DISPLAY 1.021277 (250 -275);
FORCEPROP 2 LAST CDS_LIB pure_quanta
J 0
(400 -750);
DISPLAY INVISIBLE (400 -750);
FORCEPROP 1 LAST CDS_LMAN_SYM_OUTLINE -175,100,175,-100
J 0
(400 -750);
DISPLAY 0.468085 (400 -750);
PAINT GREEN (400 -750);
DISPLAY INVISIBLE (400 -750);
FORCEPROP 1 LAST NEEDS_NO_SIZE TRUE
J 0
(400 -750);
DISPLAY 0.723404 (400 -750);
PAINT GREEN (400 -750);
DISPLAY INVISIBLE (400 -750);
FORCEPROP 1 LAST PATH I4
J 0
(400 -750);
DISPLAY 0.723404 (400 -750);
PAINT GREEN (400 -750);
DISPLAY INVISIBLE (400 -750);
FORCEPROP 1 LAST PART_NUMBER AL002G07003
J 0
(231 -516);
DISPLAY 0.723404 (231 -516);
PAINT GREEN (231 -516);
DISPLAY INVISIBLE (231 -516);
FORCEADD Q_RES..2
(3200 -350);
FORCEPROP 1 LAST LOCATION R2125
J 0
(3245 -225);
DISPLAY 0.638298 (3245 -225);
FORCEPROP 0 LAST $SEC 1
J 0
(3250 -175);
DISPLAY 0.680851 (3250 -175);
PAINT MONO (3250 -175);
DISPLAY INVISIBLE (3250 -175);
FORCEPROP 0 LAST CDS_SEC 1
J 0
(3250 -175);
DISPLAY 1.021277 (3250 -175);
DISPLAY INVISIBLE (3250 -175);
FORCEPROP 1 LASTPIN (3200 -250) $PN 1
J 0
(3205 -288);
DISPLAY 0.787234 (3205 -288);
PAINT MONO (3205 -288);
FORCEPROP 1 LASTPIN (3200 -450) $PN 2
J 0
(3205 -440);
DISPLAY 0.787234 (3205 -440);
PAINT MONO (3205 -440);
FORCEPROP 1 LAST TOLERANCE 5%
J 0
(3245 -325);
DISPLAY 0.638298 (3245 -325);
FORCEPROP 1 LAST MATERIAL CHIP
J 0
(3240 -425);
DISPLAY 0.638298 (3240 -425);
FORCEPROP 1 LAST VALUE 4.7K
J 0
(3245 -275);
DISPLAY 0.638298 (3245 -275);
FORCEPROP 1 LAST PACK_TYPE 0402LF
J 0
(3240 -525);
DISPLAY 0.638298 (3240 -525);
FORCEPROP 1 LAST WATTAGE 1/16W
J 0
(3240 -375);
DISPLAY 0.638298 (3240 -375);
FORCEPROP 2 LAST CDS_LIB pure_quanta
J 0
(3200 -350);
DISPLAY INVISIBLE (3200 -350);
FORCEPROP 1 LAST PATH I40
J 0
(3250 -175);
DISPLAY 0.978723 (3250 -175);
PAINT WHITE (3250 -175);
DISPLAY INVISIBLE (3250 -175);
FORCEPROP 1 LAST PART_NUMBER CS24702JB10
J 0
(3240 -475);
DISPLAY 0.638298 (3240 -475);
DISPLAY INVISIBLE (3240 -475);
FORCEADD OFFPAGE..2
(3375 -700);
FORCEPROP 2 LAST $XR0 145 
J 0
(3564 -700);
DISPLAY 0.638298 (3564 -700);
PAINT MONO (3564 -700);
FORCEPROP 2 LAST CDS_LIB standard
J 0
(3375 -700);
PAINT MONO (3375 -700);
DISPLAY INVISIBLE (3375 -700);
FORCEPROP 1 LAST OFFPAGE TRUE
J 0
(3700 -825);
DISPLAY 0.872340 (3700 -825);
PAINT GREEN (3700 -825);
DISPLAY INVISIBLE (3700 -825);
FORCEPROP 1 LAST COMMENT_BODY TRUE
J 0
(3330 -795);
DISPLAY 0.872340 (3330 -795);
PAINT GREEN (3330 -795);
DISPLAY INVISIBLE (3330 -795);
FORCEPROP 2 LAST PATH I41
J 0
(3575 -650);
DISPLAY 0.680851 (3575 -650);
DISPLAY INVISIBLE (3575 -650);
FORCEADD OFFPAGE..2
(3375 -800);
FORCEPROP 2 LAST $XR0 148 
J 0
(3564 -800);
DISPLAY 0.638298 (3564 -800);
PAINT MONO (3564 -800);
FORCEPROP 2 LAST CDS_LIB standard
J 0
(3375 -800);
PAINT MONO (3375 -800);
DISPLAY INVISIBLE (3375 -800);
FORCEPROP 1 LAST OFFPAGE TRUE
J 0
(3700 -925);
DISPLAY 0.872340 (3700 -925);
PAINT GREEN (3700 -925);
DISPLAY INVISIBLE (3700 -925);
FORCEPROP 1 LAST COMMENT_BODY TRUE
J 0
(3330 -895);
DISPLAY 0.872340 (3330 -895);
PAINT GREEN (3330 -895);
DISPLAY INVISIBLE (3330 -895);
FORCEPROP 2 LAST PATH I42
J 0
(3575 -750);
DISPLAY 0.680851 (3575 -750);
DISPLAY INVISIBLE (3575 -750);
FORCEADD UNIVERSAL_POWER..1
(1100 -25);
FORCEPROP 3 LASTPIN (1100 -75) SIG_NAME P3V3_AUX\g
J 0
(1110 -65);
DISPLAY 0.659574 (1110 -65);
PAINT MONO (1110 -65);
DISPLAY INVISIBLE (1110 -65);
FORCEPROP 1 LAST HDL_POWER P3V3_AUX
J 1
(1100 25);
DISPLAY 0.872340 (1100 25);
PAINT GREEN (1100 25);
FORCEPROP 2 LAST CDS_LIB pure_quanta_power
J 0
(1100 -25);
DISPLAY INVISIBLE (1100 -25);
FORCEPROP 1 LAST PATH I43
J 0
(1150 0);
DISPLAY 0.872340 (1150 0);
PAINT AQUA (1150 0);
DISPLAY INVISIBLE (1150 0);
FORCEADD UNIVERSAL_GND..1
(-2900 1900);
FORCEPROP 3 LASTPIN (-2900 1950) SIG_NAME GND\g
J 0
(-2890 1960);
DISPLAY 0.659574 (-2890 1960);
PAINT MONO (-2890 1960);
DISPLAY INVISIBLE (-2890 1960);
FORCEPROP 2 LAST CDS_LIB pure_quanta_power
J 0
(-2900 1900);
DISPLAY INVISIBLE (-2900 1900);
FORCEPROP 1 LAST HDL_POWER GND
J 1
(-2875 1825);
DISPLAY 0.872340 (-2875 1825);
PAINT GREEN (-2875 1825);
DISPLAY INVISIBLE (-2875 1825);
FORCEPROP 1 LAST PATH I5
J 0
(-2825 1900);
DISPLAY 0.872340 (-2825 1900);
PAINT AQUA (-2825 1900);
DISPLAY INVISIBLE (-2825 1900);
FORCEADD UNIVERSAL_GND..1
(1550 2800);
FORCEPROP 3 LASTPIN (1550 2850) SIG_NAME GND\g
J 0
(1560 2860);
DISPLAY 0.659574 (1560 2860);
PAINT MONO (1560 2860);
DISPLAY INVISIBLE (1560 2860);
FORCEPROP 2 LAST ROOM IO_SLOT
J 1
(1400 2850);
DISPLAY 0.744681 (1400 2850);
FORCEPROP 2 LAST CDS_LIB pure_quanta_power
J 0
(1550 2800);
DISPLAY INVISIBLE (1550 2800);
FORCEPROP 1 LAST HDL_POWER GND
J 1
(1575 2725);
DISPLAY 0.872340 (1575 2725);
PAINT GREEN (1575 2725);
DISPLAY INVISIBLE (1575 2725);
FORCEPROP 1 LAST PATH I52
J 0
(1625 2800);
DISPLAY 0.872340 (1625 2800);
PAINT AQUA (1625 2800);
DISPLAY INVISIBLE (1625 2800);
FORCEADD TAP..1
(1975 3150);
FORCEPROP 3 LASTPIN (1925 3150) SIG_NAME P3E_CPU0_P4_RX_DN<3>
J 0
(1935 3160);
DISPLAY 0.659574 (1935 3160);
PAINT MONO (1935 3160);
DISPLAY INVISIBLE (1935 3160);
FORCEPROP 1 LASTPIN (1925 3150) BN 3
J 0
(1913 3158);
DISPLAY 0.680851 (1913 3158);
PAINT GREEN (1913 3158);
FORCEPROP 2 LAST CDS_LIB standard
J 0
(1975 3150);
PAINT MONO (1975 3150);
DISPLAY INVISIBLE (1975 3150);
FORCEPROP 1 LAST BODY_TYPE PLUMBING
J 0
(1975 3200);
DISPLAY 0.872340 (1975 3200);
PAINT GREEN (1975 3200);
DISPLAY INVISIBLE (1975 3200);
FORCEPROP 1 LAST HDL_TAP TRUE
J 0
(2300 3025);
DISPLAY 0.872340 (2300 3025);
PAINT GREEN (2300 3025);
DISPLAY INVISIBLE (2300 3025);
FORCEPROP 1 LAST PATH I54
J 0
(1973 3150);
DISPLAY 0.872340 (1973 3150);
PAINT GREEN (1973 3150);
DISPLAY INVISIBLE (1973 3150);
FORCEADD TAP..1
(1825 3350);
FORCEPROP 3 LASTPIN (1775 3350) SIG_NAME P3E_CPU0_P4_RX_DP<2>
J 0
(1785 3360);
DISPLAY 0.659574 (1785 3360);
PAINT MONO (1785 3360);
DISPLAY INVISIBLE (1785 3360);
FORCEPROP 1 LASTPIN (1775 3350) BN 2
J 0
(1763 3358);
DISPLAY 0.680851 (1763 3358);
PAINT GREEN (1763 3358);
FORCEPROP 2 LAST CDS_LIB standard
J 0
(1825 3350);
PAINT MONO (1825 3350);
DISPLAY INVISIBLE (1825 3350);
FORCEPROP 1 LAST BODY_TYPE PLUMBING
J 0
(1825 3400);
DISPLAY 0.872340 (1825 3400);
PAINT GREEN (1825 3400);
DISPLAY INVISIBLE (1825 3400);
FORCEPROP 1 LAST HDL_TAP TRUE
J 0
(2150 3225);
DISPLAY 0.872340 (2150 3225);
PAINT GREEN (2150 3225);
DISPLAY INVISIBLE (2150 3225);
FORCEPROP 1 LAST PATH I55
J 0
(1823 3350);
DISPLAY 0.872340 (1823 3350);
PAINT GREEN (1823 3350);
DISPLAY INVISIBLE (1823 3350);
FORCEADD TAP..1
(1825 3200);
FORCEPROP 3 LASTPIN (1775 3200) SIG_NAME P3E_CPU0_P4_RX_DP<3>
J 0
(1785 3210);
DISPLAY 0.659574 (1785 3210);
PAINT MONO (1785 3210);
DISPLAY INVISIBLE (1785 3210);
FORCEPROP 1 LASTPIN (1775 3200) BN 3
J 0
(1763 3208);
DISPLAY 0.680851 (1763 3208);
PAINT GREEN (1763 3208);
FORCEPROP 2 LAST CDS_LIB standard
J 0
(1825 3200);
PAINT MONO (1825 3200);
DISPLAY INVISIBLE (1825 3200);
FORCEPROP 1 LAST BODY_TYPE PLUMBING
J 0
(1825 3250);
DISPLAY 0.872340 (1825 3250);
PAINT GREEN (1825 3250);
DISPLAY INVISIBLE (1825 3250);
FORCEPROP 1 LAST HDL_TAP TRUE
J 0
(2150 3075);
DISPLAY 0.872340 (2150 3075);
PAINT GREEN (2150 3075);
DISPLAY INVISIBLE (2150 3075);
FORCEPROP 1 LAST PATH I56
J 0
(1823 3200);
DISPLAY 0.872340 (1823 3200);
PAINT GREEN (1823 3200);
DISPLAY INVISIBLE (1823 3200);
FORCEADD TAP..1
(1975 3300);
FORCEPROP 3 LASTPIN (1925 3300) SIG_NAME P3E_CPU0_P4_RX_DN<2>
J 0
(1935 3310);
DISPLAY 0.659574 (1935 3310);
PAINT MONO (1935 3310);
DISPLAY INVISIBLE (1935 3310);
FORCEPROP 1 LASTPIN (1925 3300) BN 2
J 0
(1913 3308);
DISPLAY 0.680851 (1913 3308);
PAINT GREEN (1913 3308);
FORCEPROP 2 LAST CDS_LIB standard
J 0
(1975 3300);
PAINT MONO (1975 3300);
DISPLAY INVISIBLE (1975 3300);
FORCEPROP 1 LAST BODY_TYPE PLUMBING
J 0
(1975 3350);
DISPLAY 0.872340 (1975 3350);
PAINT GREEN (1975 3350);
DISPLAY INVISIBLE (1975 3350);
FORCEPROP 1 LAST HDL_TAP TRUE
J 0
(2300 3175);
DISPLAY 0.872340 (2300 3175);
PAINT GREEN (2300 3175);
DISPLAY INVISIBLE (2300 3175);
FORCEPROP 1 LAST PATH I57
J 0
(1973 3300);
DISPLAY 0.872340 (1973 3300);
PAINT GREEN (1973 3300);
DISPLAY INVISIBLE (1973 3300);
FORCEADD TAP..1
(1825 3500);
FORCEPROP 3 LASTPIN (1775 3500) SIG_NAME P3E_CPU0_P4_RX_DP<1>
J 0
(1785 3510);
DISPLAY 0.659574 (1785 3510);
PAINT MONO (1785 3510);
DISPLAY INVISIBLE (1785 3510);
FORCEPROP 1 LASTPIN (1775 3500) BN 1
J 0
(1763 3508);
DISPLAY 0.680851 (1763 3508);
PAINT GREEN (1763 3508);
FORCEPROP 2 LAST CDS_LIB standard
J 0
(1825 3500);
PAINT MONO (1825 3500);
DISPLAY INVISIBLE (1825 3500);
FORCEPROP 1 LAST BODY_TYPE PLUMBING
J 0
(1825 3550);
DISPLAY 0.872340 (1825 3550);
PAINT GREEN (1825 3550);
DISPLAY INVISIBLE (1825 3550);
FORCEPROP 1 LAST HDL_TAP TRUE
J 0
(2150 3375);
DISPLAY 0.872340 (2150 3375);
PAINT GREEN (2150 3375);
DISPLAY INVISIBLE (2150 3375);
FORCEPROP 1 LAST PATH I58
J 0
(1823 3500);
DISPLAY 0.872340 (1823 3500);
PAINT GREEN (1823 3500);
DISPLAY INVISIBLE (1823 3500);
FORCEADD TAP..1
(1825 3650);
FORCEPROP 3 LASTPIN (1775 3650) SIG_NAME P3E_CPU0_P4_RX_DP<0>
J 0
(1785 3660);
DISPLAY 0.659574 (1785 3660);
PAINT MONO (1785 3660);
DISPLAY INVISIBLE (1785 3660);
FORCEPROP 1 LASTPIN (1775 3650) BN 0
J 0
(1763 3658);
DISPLAY 0.680851 (1763 3658);
PAINT GREEN (1763 3658);
FORCEPROP 2 LAST CDS_LIB standard
J 0
(1825 3650);
PAINT MONO (1825 3650);
DISPLAY INVISIBLE (1825 3650);
FORCEPROP 1 LAST BODY_TYPE PLUMBING
J 0
(1825 3700);
DISPLAY 0.872340 (1825 3700);
PAINT GREEN (1825 3700);
DISPLAY INVISIBLE (1825 3700);
FORCEPROP 1 LAST HDL_TAP TRUE
J 0
(2150 3525);
DISPLAY 0.872340 (2150 3525);
PAINT GREEN (2150 3525);
DISPLAY INVISIBLE (2150 3525);
FORCEPROP 1 LAST PATH I59
J 0
(1823 3650);
DISPLAY 0.872340 (1823 3650);
PAINT GREEN (1823 3650);
DISPLAY INVISIBLE (1823 3650);
FORCEADD Q_RES..2
(-2900 2150);
FORCEPROP 1 LAST LOCATION R10296
J 0
(-2855 2275);
DISPLAY 0.978723 (-2855 2275);
FORCEPROP 0 LAST $SEC 1
J 0
(-2850 2325);
DISPLAY 0.680851 (-2850 2325);
PAINT MONO (-2850 2325);
DISPLAY INVISIBLE (-2850 2325);
FORCEPROP 0 LAST CDS_SEC 1
J 0
(-2850 2325);
DISPLAY 1.021277 (-2850 2325);
DISPLAY INVISIBLE (-2850 2325);
FORCEPROP 1 LASTPIN (-2900 2250) $PN 1
J 0
(-2895 2212);
DISPLAY 0.787234 (-2895 2212);
PAINT MONO (-2895 2212);
FORCEPROP 1 LASTPIN (-2900 2050) $PN 2
J 0
(-2895 2060);
DISPLAY 0.787234 (-2895 2060);
PAINT MONO (-2895 2060);
FORCEPROP 1 LAST TOLERANCE 1%
J 0
(-2855 2175);
DISPLAY 0.638298 (-2855 2175);
FORCEPROP 1 LAST PACK_TYPE 0402LF
J 0
(-2860 2025);
DISPLAY 0.638298 (-2860 2025);
FORCEPROP 1 LAST WATTAGE 1/16W
J 0
(-2860 2125);
DISPLAY 0.638298 (-2860 2125);
FORCEPROP 1 LAST MATERIAL CHIP
J 0
(-2860 2075);
DISPLAY 0.638298 (-2860 2075);
FORCEPROP 1 LAST VALUE 1K
J 0
(-2855 2225);
DISPLAY 0.638298 (-2855 2225);
FORCEPROP 2 LAST CDS_LIB pure_quanta
J 0
(-2900 2150);
DISPLAY INVISIBLE (-2900 2150);
FORCEPROP 1 LAST PATH I6
J 0
(-2850 2325);
DISPLAY 0.978723 (-2850 2325);
PAINT WHITE (-2850 2325);
DISPLAY INVISIBLE (-2850 2325);
FORCEPROP 1 LAST PART_NUMBER CS21002FB06
J 0
(-2860 1975);
DISPLAY 0.638298 (-2860 1975);
DISPLAY INVISIBLE (-2860 1975);
FORCEADD TAP..1
(1975 3450);
FORCEPROP 3 LASTPIN (1925 3450) SIG_NAME P3E_CPU0_P4_RX_DN<1>
J 0
(1935 3460);
DISPLAY 0.659574 (1935 3460);
PAINT MONO (1935 3460);
DISPLAY INVISIBLE (1935 3460);
FORCEPROP 1 LASTPIN (1925 3450) BN 1
J 0
(1913 3458);
DISPLAY 0.680851 (1913 3458);
PAINT GREEN (1913 3458);
FORCEPROP 2 LAST CDS_LIB standard
J 0
(1975 3450);
PAINT MONO (1975 3450);
DISPLAY INVISIBLE (1975 3450);
FORCEPROP 1 LAST BODY_TYPE PLUMBING
J 0
(1975 3500);
DISPLAY 0.872340 (1975 3500);
PAINT GREEN (1975 3500);
DISPLAY INVISIBLE (1975 3500);
FORCEPROP 1 LAST HDL_TAP TRUE
J 0
(2300 3325);
DISPLAY 0.872340 (2300 3325);
PAINT GREEN (2300 3325);
DISPLAY INVISIBLE (2300 3325);
FORCEPROP 1 LAST PATH I60
J 0
(1973 3450);
DISPLAY 0.872340 (1973 3450);
PAINT GREEN (1973 3450);
DISPLAY INVISIBLE (1973 3450);
FORCEADD TAP..1
(1975 3600);
FORCEPROP 3 LASTPIN (1925 3600) SIG_NAME P3E_CPU0_P4_RX_DN<0>
J 0
(1935 3610);
DISPLAY 0.659574 (1935 3610);
PAINT MONO (1935 3610);
DISPLAY INVISIBLE (1935 3610);
FORCEPROP 1 LASTPIN (1925 3600) BN 0
J 0
(1913 3608);
DISPLAY 0.680851 (1913 3608);
PAINT GREEN (1913 3608);
FORCEPROP 2 LAST CDS_LIB standard
J 0
(1975 3600);
PAINT MONO (1975 3600);
DISPLAY INVISIBLE (1975 3600);
FORCEPROP 1 LAST BODY_TYPE PLUMBING
J 0
(1975 3650);
DISPLAY 0.872340 (1975 3650);
PAINT GREEN (1975 3650);
DISPLAY INVISIBLE (1975 3650);
FORCEPROP 1 LAST HDL_TAP TRUE
J 0
(2300 3475);
DISPLAY 0.872340 (2300 3475);
DISPLAY INVISIBLE (2300 3475);
FORCEPROP 1 LAST PATH I61
J 0
(1973 3600);
DISPLAY 0.872340 (1973 3600);
PAINT GREEN (1973 3600);
DISPLAY INVISIBLE (1973 3600);
FORCEADD UNIVERSAL_POWER..1
(2925 0);
FORCEPROP 3 LASTPIN (2925 -50) SIG_NAME P3V3_AUX\g
J 0
(2935 -40);
DISPLAY 0.659574 (2935 -40);
PAINT MONO (2935 -40);
DISPLAY INVISIBLE (2935 -40);
FORCEPROP 1 LAST HDL_POWER P3V3_AUX
J 1
(2925 50);
DISPLAY 0.872340 (2925 50);
PAINT GREEN (2925 50);
FORCEPROP 2 LAST CDS_LIB pure_quanta_power
J 0
(2925 0);
DISPLAY INVISIBLE (2925 0);
FORCEPROP 1 LAST PATH I64
J 0
(2975 25);
DISPLAY 0.872340 (2975 25);
PAINT AQUA (2975 25);
DISPLAY INVISIBLE (2975 25);
FORCEADD Q_CAP..1
(2475 2675);
FORCEPROP 1 LAST LOCATION C1276
J 0
(2525 2775);
DISPLAY 0.787234 (2525 2775);
FORCEPROP 2 LAST $SEC 1
J 0
(2525 2875);
DISPLAY 0.680851 (2525 2875);
PAINT MONO (2525 2875);
DISPLAY INVISIBLE (2525 2875);
FORCEPROP 2 LAST CDS_SEC 1
J 0
(2525 2875);
DISPLAY 1.021277 (2525 2875);
DISPLAY INVISIBLE (2525 2875);
FORCEPROP 1 LASTPIN (2475 2775) $PN 1
J 0
(2485 2755);
DISPLAY 0.787234 (2485 2755);
FORCEPROP 1 LASTPIN (2475 2575) $PN 2
J 0
(2485 2555);
DISPLAY 0.787234 (2485 2555);
FORCEPROP 1 LAST VALUE 22UF
J 0
(2525 2725);
DISPLAY 0.638298 (2525 2725);
FORCEPROP 1 LAST VOLTAGE 16V
J 0
(2525 2675);
DISPLAY 0.638298 (2525 2675);
FORCEPROP 1 LAST MATERIAL X6S
J 0
(2525 2575);
DISPLAY 0.638298 (2525 2575);
FORCEPROP 1 LAST PACK_TYPE C0805
J 0
(2525 2525);
DISPLAY 0.638298 (2525 2525);
FORCEPROP 1 LAST TOLERANCE 20%
J 0
(2525 2625);
DISPLAY 0.638298 (2525 2625);
FORCEPROP 2 LAST CDS_LIB pure_quanta
J 0
(2475 2675);
PAINT MONO (2475 2675);
DISPLAY INVISIBLE (2475 2675);
FORCEPROP 1 LAST PATH I66
J 0
(2525 2825);
DISPLAY 0.978723 (2525 2825);
PAINT WHITE (2525 2825);
DISPLAY INVISIBLE (2525 2825);
FORCEPROP 1 LAST PART_NUMBER CH6223MEA01
J 0
(2525 2475);
DISPLAY 0.808511 (2525 2475);
DISPLAY INVISIBLE (2525 2475);
FORCEADD Q_CAP..1
(2750 2675);
FORCEPROP 1 LAST LOCATION C1277
J 0
(2800 2775);
DISPLAY 0.787234 (2800 2775);
FORCEPROP 2 LAST $SEC 1
J 0
(2800 2875);
DISPLAY 0.680851 (2800 2875);
PAINT MONO (2800 2875);
DISPLAY INVISIBLE (2800 2875);
FORCEPROP 2 LAST CDS_SEC 1
J 0
(2800 2875);
DISPLAY 1.021277 (2800 2875);
DISPLAY INVISIBLE (2800 2875);
FORCEPROP 1 LASTPIN (2750 2775) $PN 1
J 0
(2760 2755);
DISPLAY 0.787234 (2760 2755);
FORCEPROP 1 LASTPIN (2750 2575) $PN 2
J 0
(2760 2555);
DISPLAY 0.787234 (2760 2555);
FORCEPROP 1 LAST VOLTAGE 16V
J 0
(2800 2675);
DISPLAY 0.638298 (2800 2675);
FORCEPROP 1 LAST PACK_TYPE C0805
J 0
(2800 2475);
DISPLAY 0.638298 (2800 2475);
FORCEPROP 1 LAST MATERIAL X6S
J 0
(2800 2575);
DISPLAY 0.638298 (2800 2575);
FORCEPROP 1 LAST TOLERANCE 20%
J 0
(2800 2625);
DISPLAY 0.638298 (2800 2625);
FORCEPROP 1 LAST VALUE 22UF
J 0
(2800 2725);
DISPLAY 0.638298 (2800 2725);
FORCEPROP 2 LAST CDS_LIB pure_quanta
J 0
(2750 2675);
PAINT MONO (2750 2675);
DISPLAY INVISIBLE (2750 2675);
FORCEPROP 1 LAST PATH I67
J 0
(2800 2825);
DISPLAY 0.978723 (2800 2825);
PAINT WHITE (2800 2825);
DISPLAY INVISIBLE (2800 2825);
FORCEPROP 1 LAST PART_NUMBER CH6223MEA01
J 0
(2800 2525);
DISPLAY 0.638298 (2800 2525);
DISPLAY INVISIBLE (2800 2525);
FORCEADD Q_CAP..1
(3150 2675);
FORCEPROP 1 LAST LOCATION C1278
J 0
(3200 2775);
DISPLAY 0.787234 (3200 2775);
FORCEPROP 2 LAST $SEC 1
J 0
(3200 2875);
DISPLAY 0.680851 (3200 2875);
PAINT MONO (3200 2875);
DISPLAY INVISIBLE (3200 2875);
FORCEPROP 2 LAST CDS_SEC 1
J 0
(3200 2875);
DISPLAY 1.021277 (3200 2875);
DISPLAY INVISIBLE (3200 2875);
FORCEPROP 1 LASTPIN (3150 2775) $PN 1
J 0
(3160 2755);
DISPLAY 0.787234 (3160 2755);
FORCEPROP 1 LASTPIN (3150 2575) $PN 2
J 0
(3160 2555);
DISPLAY 0.787234 (3160 2555);
FORCEPROP 1 LAST MATERIAL X7R
J 0
(3200 2575);
DISPLAY 0.638298 (3200 2575);
FORCEPROP 1 LAST TOLERANCE 10%
J 0
(3200 2625);
DISPLAY 0.638298 (3200 2625);
FORCEPROP 1 LAST VALUE 0.1UF
J 0
(3200 2725);
DISPLAY 0.638298 (3200 2725);
FORCEPROP 1 LAST VOLTAGE 25V
J 0
(3200 2675);
DISPLAY 0.638298 (3200 2675);
FORCEPROP 1 LAST PACK_TYPE 0402
J 0
(3200 2525);
DISPLAY 0.638298 (3200 2525);
FORCEPROP 2 LAST CDS_LIB pure_quanta
J 0
(3150 2675);
PAINT MONO (3150 2675);
DISPLAY INVISIBLE (3150 2675);
FORCEPROP 1 LAST PATH I68
J 0
(3200 2825);
DISPLAY 0.978723 (3200 2825);
PAINT WHITE (3200 2825);
DISPLAY INVISIBLE (3200 2825);
FORCEPROP 1 LAST PART_NUMBER CH4104K1B00
J 0
(3200 2525);
DISPLAY 0.808511 (3200 2525);
DISPLAY INVISIBLE (3200 2525);
FORCEADD UNIVERSAL_POWER..1
(2475 3025);
FORCEPROP 3 LASTPIN (2475 2975) SIG_NAME P12V_E1S_0_R\g
J 0
(2485 2985);
DISPLAY 0.659574 (2485 2985);
PAINT MONO (2485 2985);
DISPLAY INVISIBLE (2485 2985);
FORCEPROP 1 LAST HDL_POWER P12V_E1S_0_R
J 1
(2475 3075);
DISPLAY 0.872340 (2475 3075);
PAINT GREEN (2475 3075);
FORCEPROP 2 LAST CDS_LIB pure_quanta_power
J 0
(2475 3025);
PAINT MONO (2475 3025);
DISPLAY INVISIBLE (2475 3025);
FORCEPROP 1 LAST PATH I69
J 0
(2525 3050);
DISPLAY 0.872340 (2525 3050);
PAINT AQUA (2525 3050);
DISPLAY INVISIBLE (2525 3050);
FORCEADD Q_RES..2
(-2900 2650);
FORCEPROP 1 LAST LOCATION R3771
J 0
(-2855 2775);
DISPLAY 0.723404 (-2855 2775);
PAINT AQUA (-2855 2775);
FORCEPROP 0 LAST $SEC 1
J 0
(-2850 2825);
DISPLAY 0.680851 (-2850 2825);
PAINT MONO (-2850 2825);
DISPLAY INVISIBLE (-2850 2825);
FORCEPROP 0 LAST CDS_SEC 1
J 0
(-2850 2825);
DISPLAY 1.021277 (-2850 2825);
DISPLAY INVISIBLE (-2850 2825);
FORCEPROP 1 LASTPIN (-2900 2750) $PN 1
J 0
(-2895 2712);
DISPLAY 0.787234 (-2895 2712);
PAINT MONO (-2895 2712);
FORCEPROP 1 LASTPIN (-2900 2550) $PN 2
J 0
(-2895 2560);
DISPLAY 0.787234 (-2895 2560);
PAINT MONO (-2895 2560);
FORCEPROP 1 LAST VALUE 10K
J 0
(-2855 2725);
DISPLAY 0.723404 (-2855 2725);
PAINT SKYBLUE (-2855 2725);
FORCEPROP 1 LAST PACK_TYPE 0402LF
J 0
(-2850 2525);
DISPLAY 0.723404 (-2850 2525);
PAINT SKYBLUE (-2850 2525);
FORCEPROP 1 LAST MATERIAL CHIP
J 0
(-2860 2575);
DISPLAY 0.723404 (-2860 2575);
PAINT SKYBLUE (-2860 2575);
FORCEPROP 1 LAST WATTAGE 1/16W
J 0
(-2860 2625);
DISPLAY 0.723404 (-2860 2625);
PAINT SKYBLUE (-2860 2625);
FORCEPROP 1 LAST TOLERANCE 1%
J 0
(-2855 2675);
DISPLAY 0.723404 (-2855 2675);
PAINT SKYBLUE (-2855 2675);
FORCEPROP 2 LAST CDS_LIB pure_quanta
J 0
(-2900 2650);
DISPLAY INVISIBLE (-2900 2650);
FORCEPROP 1 LAST PATH I7
J 0
(-2850 2825);
DISPLAY 0.978723 (-2850 2825);
PAINT WHITE (-2850 2825);
DISPLAY INVISIBLE (-2850 2825);
FORCEPROP 1 LAST PART_NUMBER CS31002FB08
J 0
(-2860 2525);
DISPLAY 0.723404 (-2860 2525);
PAINT WHITE (-2860 2525);
DISPLAY INVISIBLE (-2860 2525);
FORCEADD OFFPAGE..2
(3050 3625);
FORCEPROP 2 LAST $XR0 26 
J 0
(3239 3625);
DISPLAY 0.638298 (3239 3625);
PAINT MONO (3239 3625);
FORCEPROP 2 LAST CDS_LIB standard
J 0
(3050 3625);
DISPLAY INVISIBLE (3050 3625);
FORCEPROP 1 LAST OFFPAGE TRUE
J 0
(3375 3500);
DISPLAY 0.872340 (3375 3500);
PAINT GREEN (3375 3500);
DISPLAY INVISIBLE (3375 3500);
FORCEPROP 1 LAST COMMENT_BODY TRUE
J 0
(3005 3530);
DISPLAY 0.872340 (3005 3530);
PAINT GREEN (3005 3530);
DISPLAY INVISIBLE (3005 3530);
FORCEPROP 2 LAST PATH I70
J 0
(3250 3675);
DISPLAY 0.680851 (3250 3675);
DISPLAY INVISIBLE (3250 3675);
FORCEADD OFFPAGE..2
(3050 3675);
FORCEPROP 2 LAST $XR0 26 
J 0
(3239 3675);
DISPLAY 0.638298 (3239 3675);
PAINT MONO (3239 3675);
FORCEPROP 2 LAST CDS_LIB standard
J 0
(3050 3675);
DISPLAY INVISIBLE (3050 3675);
FORCEPROP 1 LAST OFFPAGE TRUE
J 0
(3375 3550);
DISPLAY 0.872340 (3375 3550);
PAINT GREEN (3375 3550);
DISPLAY INVISIBLE (3375 3550);
FORCEPROP 1 LAST COMMENT_BODY TRUE
J 0
(3005 3580);
DISPLAY 0.872340 (3005 3580);
PAINT GREEN (3005 3580);
DISPLAY INVISIBLE (3005 3580);
FORCEPROP 2 LAST PATH I71
J 0
(3250 3725);
DISPLAY 0.680851 (3250 3725);
DISPLAY INVISIBLE (3250 3725);
FORCEADD OFFPAGE..2
(3025 3950);
FORCEPROP 2 LAST $XR2 82 
J 0
(3394 3950);
DISPLAY 0.638298 (3394 3950);
PAINT MONO (3394 3950);
FORCEPROP 2 LAST $XR1 80 
J 0
(3304 3950);
DISPLAY 0.638298 (3304 3950);
PAINT MONO (3304 3950);
FORCEPROP 2 LAST $XR0 83 
J 0
(3214 3950);
DISPLAY 0.638298 (3214 3950);
PAINT MONO (3214 3950);
FORCEPROP 2 LAST CDS_LIB standard
J 0
(3025 3950);
DISPLAY INVISIBLE (3025 3950);
FORCEPROP 1 LAST OFFPAGE TRUE
J 0
(3350 3825);
DISPLAY 0.872340 (3350 3825);
PAINT GREEN (3350 3825);
DISPLAY INVISIBLE (3350 3825);
FORCEPROP 1 LAST COMMENT_BODY TRUE
J 0
(2980 3855);
DISPLAY 0.872340 (2980 3855);
PAINT GREEN (2980 3855);
DISPLAY INVISIBLE (2980 3855);
FORCEPROP 2 LAST PATH I72
J 0
(3475 4000);
DISPLAY 0.680851 (3475 4000);
DISPLAY INVISIBLE (3475 4000);
FORCEADD UNIVERSAL_GND..1
(3425 2325);
FORCEPROP 3 LASTPIN (3425 2375) SIG_NAME GND\g
J 0
(3435 2385);
DISPLAY 0.659574 (3435 2385);
PAINT MONO (3435 2385);
DISPLAY INVISIBLE (3435 2385);
FORCEPROP 2 LAST ROOM IO_SLOT
J 1
(3200 2400);
DISPLAY 0.744681 (3200 2400);
FORCEPROP 2 LAST CDS_LIB pure_quanta_power
J 0
(3425 2325);
PAINT MONO (3425 2325);
DISPLAY INVISIBLE (3425 2325);
FORCEPROP 1 LAST HDL_POWER GND
J 1
(3450 2250);
DISPLAY 0.872340 (3450 2250);
PAINT GREEN (3450 2250);
DISPLAY INVISIBLE (3450 2250);
FORCEPROP 1 LAST PATH I73
J 0
(3500 2325);
DISPLAY 0.872340 (3500 2325);
PAINT AQUA (3500 2325);
DISPLAY INVISIBLE (3500 2325);
FORCEADD Q_CAP..1
(3425 2675);
FORCEPROP 1 LAST LOCATION C1279
J 0
(3475 2775);
DISPLAY 0.787234 (3475 2775);
FORCEPROP 2 LAST $SEC 1
J 0
(3475 2875);
DISPLAY 0.680851 (3475 2875);
PAINT MONO (3475 2875);
DISPLAY INVISIBLE (3475 2875);
FORCEPROP 2 LAST CDS_SEC 1
J 0
(3475 2875);
DISPLAY 1.021277 (3475 2875);
DISPLAY INVISIBLE (3475 2875);
FORCEPROP 1 LASTPIN (3425 2775) $PN 1
J 0
(3435 2755);
DISPLAY 0.787234 (3435 2755);
FORCEPROP 1 LASTPIN (3425 2575) $PN 2
J 0
(3435 2555);
DISPLAY 0.787234 (3435 2555);
FORCEPROP 1 LAST PACK_TYPE 0402
J 0
(3475 2525);
DISPLAY 0.638298 (3475 2525);
FORCEPROP 1 LAST VALUE 0.1UF
J 0
(3475 2725);
DISPLAY 0.638298 (3475 2725);
FORCEPROP 1 LAST VOLTAGE 25V
J 0
(3475 2675);
DISPLAY 0.638298 (3475 2675);
FORCEPROP 1 LAST MATERIAL X7R
J 0
(3475 2575);
DISPLAY 0.638298 (3475 2575);
FORCEPROP 1 LAST TOLERANCE 10%
J 0
(3475 2625);
DISPLAY 0.638298 (3475 2625);
FORCEPROP 2 LAST CDS_LIB pure_quanta
J 0
(3425 2675);
PAINT MONO (3425 2675);
DISPLAY INVISIBLE (3425 2675);
FORCEPROP 1 LAST PATH I74
J 0
(3475 2825);
DISPLAY 0.978723 (3475 2825);
PAINT WHITE (3475 2825);
DISPLAY INVISIBLE (3475 2825);
FORCEPROP 1 LAST PART_NUMBER CH4104K1B00
J 0
(3475 2525);
DISPLAY 0.808511 (3475 2525);
DISPLAY INVISIBLE (3475 2525);
FORCEADD Q_RES..2
(4000 3700);
FORCEPROP 1 LAST LOCATION R2426
J 0
(4045 3825);
DISPLAY 0.638298 (4045 3825);
FORCEPROP 0 LAST $SEC 1
J 0
(4050 3875);
DISPLAY 0.680851 (4050 3875);
PAINT MONO (4050 3875);
DISPLAY INVISIBLE (4050 3875);
FORCEPROP 0 LAST CDS_SEC 1
J 0
(4050 3875);
DISPLAY 1.021277 (4050 3875);
DISPLAY INVISIBLE (4050 3875);
FORCEPROP 1 LASTPIN (4000 3800) $PN 1
J 0
(4005 3762);
DISPLAY 0.787234 (4005 3762);
PAINT MONO (4005 3762);
FORCEPROP 1 LASTPIN (4000 3600) $PN 2
J 0
(4005 3610);
DISPLAY 0.787234 (4005 3610);
PAINT MONO (4005 3610);
FORCEPROP 1 LAST TOLERANCE 1%
J 0
(4045 3725);
DISPLAY 0.510638 (4045 3725);
FORCEPROP 1 LAST WATTAGE 1/16W
J 0
(4040 3675);
DISPLAY 0.510638 (4040 3675);
FORCEPROP 1 LAST MATERIAL EMPTY
J 0
(4040 3625);
DISPLAY 0.510638 (4040 3625);
PAINT RED (4040 3625);
FORCEPROP 1 LAST PACK_TYPE 0402LF
J 0
(4040 3575);
DISPLAY 0.510638 (4040 3575);
FORCEPROP 1 LAST VALUE 100
J 0
(4045 3775);
DISPLAY 0.510638 (4045 3775);
FORCEPROP 2 LAST CDS_LIB pure_quanta
J 0
(4000 3700);
DISPLAY INVISIBLE (4000 3700);
FORCEPROP 1 LAST PATH I75
J 0
(4050 3875);
DISPLAY 0.978723 (4050 3875);
PAINT WHITE (4050 3875);
DISPLAY INVISIBLE (4050 3875);
FORCEPROP 1 LAST PART_NUMBER CS11002FB07
J 0
(4040 3525);
DISPLAY 0.510638 (4040 3525);
DISPLAY INVISIBLE (4040 3525);
FORCEADD UNIVERSAL_GND..1
(4000 3475);
FORCEPROP 3 LASTPIN (4000 3525) SIG_NAME GND\g
J 0
(4010 3535);
DISPLAY 0.659574 (4010 3535);
PAINT MONO (4010 3535);
DISPLAY INVISIBLE (4010 3535);
FORCEPROP 2 LAST ROOM IO_SLOT
J 1
(3775 3550);
DISPLAY 0.744681 (3775 3550);
FORCEPROP 2 LAST CDS_LIB pure_quanta_power
J 0
(4000 3475);
DISPLAY INVISIBLE (4000 3475);
FORCEPROP 1 LAST HDL_POWER GND
J 1
(4025 3400);
DISPLAY 0.872340 (4025 3400);
PAINT GREEN (4025 3400);
DISPLAY INVISIBLE (4025 3400);
FORCEPROP 1 LAST PATH I76
J 0
(4075 3475);
DISPLAY 0.872340 (4075 3475);
PAINT AQUA (4075 3475);
DISPLAY INVISIBLE (4075 3475);
FORCEADD UNIVERSAL_POWER..1
(2450 4675);
FORCEPROP 3 LASTPIN (2450 4625) SIG_NAME P3V3_E1S_0\g
J 0
(2460 4635);
DISPLAY 0.659574 (2460 4635);
PAINT MONO (2460 4635);
DISPLAY INVISIBLE (2460 4635);
FORCEPROP 1 LAST HDL_POWER P3V3_E1S_0
J 1
(2450 4725);
DISPLAY 0.872340 (2450 4725);
PAINT GREEN (2450 4725);
FORCEPROP 2 LAST CDS_LIB pure_quanta_power
J 0
(2450 4675);
PAINT MONO (2450 4675);
DISPLAY INVISIBLE (2450 4675);
FORCEPROP 1 LAST PATH I78
J 0
(2500 4700);
DISPLAY 0.872340 (2500 4700);
PAINT AQUA (2500 4700);
DISPLAY INVISIBLE (2500 4700);
FORCEADD Q_RES..2
(2900 4475);
FORCEPROP 1 LAST LOCATION R10287
J 0
(2945 4600);
DISPLAY 0.638298 (2945 4600);
FORCEPROP 0 LAST $SEC 1
J 0
(2950 4650);
DISPLAY 0.680851 (2950 4650);
PAINT MONO (2950 4650);
DISPLAY INVISIBLE (2950 4650);
FORCEPROP 0 LAST CDS_SEC 1
J 0
(2950 4650);
DISPLAY 1.021277 (2950 4650);
DISPLAY INVISIBLE (2950 4650);
FORCEPROP 1 LASTPIN (2900 4575) $PN 1
J 0
(2905 4537);
DISPLAY 0.787234 (2905 4537);
PAINT MONO (2905 4537);
FORCEPROP 1 LASTPIN (2900 4375) $PN 2
J 0
(2905 4385);
DISPLAY 0.787234 (2905 4385);
PAINT MONO (2905 4385);
FORCEPROP 1 LAST TOLERANCE 1%
J 0
(2945 4500);
DISPLAY 0.510638 (2945 4500);
FORCEPROP 1 LAST VALUE 10K
J 0
(2945 4550);
DISPLAY 0.510638 (2945 4550);
FORCEPROP 1 LAST MATERIAL CHIP
J 0
(2940 4400);
DISPLAY 0.510638 (2940 4400);
FORCEPROP 1 LAST PACK_TYPE 0402LF
J 0
(2940 4350);
DISPLAY 0.510638 (2940 4350);
FORCEPROP 1 LAST WATTAGE 1/16W
J 0
(2940 4450);
DISPLAY 0.510638 (2940 4450);
FORCEPROP 2 LAST CDS_LIB pure_quanta
J 0
(2900 4475);
DISPLAY INVISIBLE (2900 4475);
FORCEPROP 1 LAST PATH I79
J 0
(2950 4650);
DISPLAY 0.978723 (2950 4650);
PAINT WHITE (2950 4650);
DISPLAY INVISIBLE (2950 4650);
FORCEPROP 1 LAST PART_NUMBER CS31002FB08
J 0
(2940 4300);
DISPLAY 0.510638 (2940 4300);
DISPLAY INVISIBLE (2940 4300);
FORCEADD UNIVERSAL_POWER..1
(-2900 2900);
FORCEPROP 3 LASTPIN (-2900 2850) SIG_NAME P3V3_AUX\g
J 0
(-2890 2860);
DISPLAY 0.659574 (-2890 2860);
PAINT MONO (-2890 2860);
DISPLAY INVISIBLE (-2890 2860);
FORCEPROP 1 LAST HDL_POWER P3V3_AUX
J 1
(-2900 2950);
DISPLAY 0.872340 (-2900 2950);
PAINT GREEN (-2900 2950);
FORCEPROP 2 LAST CDS_LIB pure_quanta_power
J 0
(-2900 2900);
DISPLAY INVISIBLE (-2900 2900);
FORCEPROP 1 LAST PATH I8
J 0
(-2850 2925);
DISPLAY 0.872340 (-2850 2925);
PAINT AQUA (-2850 2925);
DISPLAY INVISIBLE (-2850 2925);
FORCEADD OFFPAGE..4
(3025 4050);
FORCEPROP 2 LAST $XR0 145 
J 0
(3211 4050);
DISPLAY 0.638298 (3211 4050);
PAINT MONO (3211 4050);
FORCEPROP 2 LAST CDS_LIB standard
J 0
(3025 4050);
PAINT MONO (3025 4050);
DISPLAY INVISIBLE (3025 4050);
FORCEPROP 1 LAST OFFPAGE TRUE
J 0
(3350 3925);
DISPLAY 0.872340 (3350 3925);
PAINT GREEN (3350 3925);
DISPLAY INVISIBLE (3350 3925);
FORCEPROP 1 LAST COMMENT_BODY TRUE
J 0
(3000 3950);
DISPLAY 0.872340 (3000 3950);
PAINT GREEN (3000 3950);
DISPLAY INVISIBLE (3000 3950);
FORCEPROP 2 LAST PATH I80
J 0
(3225 4100);
DISPLAY 0.680851 (3225 4100);
DISPLAY INVISIBLE (3225 4100);
FORCEADD OFFPAGE..4
(3025 4100);
FORCEPROP 2 LAST $XR0 145 
J 0
(3211 4100);
DISPLAY 0.638298 (3211 4100);
PAINT MONO (3211 4100);
FORCEPROP 2 LAST CDS_LIB standard
J 0
(3025 4100);
DISPLAY INVISIBLE (3025 4100);
FORCEPROP 1 LAST OFFPAGE TRUE
J 0
(3350 3975);
DISPLAY 0.872340 (3350 3975);
PAINT GREEN (3350 3975);
DISPLAY INVISIBLE (3350 3975);
FORCEPROP 1 LAST COMMENT_BODY TRUE
J 0
(3000 4000);
DISPLAY 0.872340 (3000 4000);
PAINT GREEN (3000 4000);
DISPLAY INVISIBLE (3000 4000);
FORCEPROP 2 LAST PATH I81
J 0
(3250 4150);
DISPLAY 0.680851 (3250 4150);
DISPLAY INVISIBLE (3250 4150);
FORCEADD OFFPAGE..3
(3025 4150);
FORCEPROP 2 LAST $XR0 148 
J 0
(3239 4150);
DISPLAY 0.638298 (3239 4150);
PAINT MONO (3239 4150);
FORCEPROP 2 LAST CDS_LIB standard
J 0
(3025 4150);
PAINT MONO (3025 4150);
DISPLAY INVISIBLE (3025 4150);
FORCEPROP 1 LAST OFFPAGE TRUE
J 0
(3350 4025);
DISPLAY 0.872340 (3350 4025);
DISPLAY INVISIBLE (3350 4025);
FORCEPROP 1 LAST COMMENT_BODY TRUE
J 0
(2975 4050);
DISPLAY 0.872340 (2975 4050);
PAINT GREEN (2975 4050);
DISPLAY INVISIBLE (2975 4050);
FORCEPROP 2 LAST PATH I82
J 0
(3250 4200);
DISPLAY 0.680851 (3250 4200);
DISPLAY INVISIBLE (3250 4200);
FORCEADD OFFPAGE..4
(3025 4200);
FORCEPROP 2 LAST $XR0 148 
J 0
(3211 4200);
DISPLAY 0.638298 (3211 4200);
PAINT MONO (3211 4200);
FORCEPROP 2 LAST CDS_LIB standard
J 0
(3025 4200);
PAINT MONO (3025 4200);
DISPLAY INVISIBLE (3025 4200);
FORCEPROP 1 LAST OFFPAGE TRUE
J 0
(3350 4075);
DISPLAY 0.872340 (3350 4075);
PAINT GREEN (3350 4075);
DISPLAY INVISIBLE (3350 4075);
FORCEPROP 1 LAST COMMENT_BODY TRUE
J 0
(3000 4100);
DISPLAY 0.872340 (3000 4100);
PAINT GREEN (3000 4100);
DISPLAY INVISIBLE (3000 4100);
FORCEPROP 2 LAST PATH I83
J 0
(3225 4250);
DISPLAY 0.680851 (3225 4250);
DISPLAY INVISIBLE (3225 4250);
FORCEADD OFFPAGE..2
(4225 4000);
FORCEPROP 2 LAST $XR0 80 
J 0
(4414 4000);
DISPLAY 0.638298 (4414 4000);
PAINT MONO (4414 4000);
FORCEPROP 2 LAST CDS_LIB standard
J 0
(4225 4000);
DISPLAY INVISIBLE (4225 4000);
FORCEPROP 1 LAST OFFPAGE TRUE
J 0
(4550 3875);
DISPLAY 0.872340 (4550 3875);
PAINT GREEN (4550 3875);
DISPLAY INVISIBLE (4550 3875);
FORCEPROP 1 LAST COMMENT_BODY TRUE
J 0
(4180 3905);
DISPLAY 0.872340 (4180 3905);
PAINT GREEN (4180 3905);
DISPLAY INVISIBLE (4180 3905);
FORCEPROP 2 LAST PATH I85
J 0
(4425 4050);
DISPLAY 0.680851 (4425 4050);
DISPLAY INVISIBLE (4425 4050);
FORCEADD UNIVERSAL_GND..1
(4750 2325);
FORCEPROP 3 LASTPIN (4750 2375) SIG_NAME GND\g
J 0
(4760 2385);
DISPLAY 0.659574 (4760 2385);
PAINT MONO (4760 2385);
DISPLAY INVISIBLE (4760 2385);
FORCEPROP 2 LAST ROOM IO_SLOT
J 1
(4525 2400);
DISPLAY 0.744681 (4525 2400);
FORCEPROP 2 LAST CDS_LIB pure_quanta_power
J 0
(4750 2325);
PAINT MONO (4750 2325);
DISPLAY INVISIBLE (4750 2325);
FORCEPROP 1 LAST HDL_POWER GND
J 1
(4775 2250);
DISPLAY 0.872340 (4775 2250);
PAINT GREEN (4775 2250);
DISPLAY INVISIBLE (4775 2250);
FORCEPROP 1 LAST PATH I86
J 0
(4825 2325);
DISPLAY 0.872340 (4825 2325);
PAINT AQUA (4825 2325);
DISPLAY INVISIBLE (4825 2325);
FORCEADD Q_CAP..1
(4500 2675);
FORCEPROP 1 LAST LOCATION C1282
J 0
(4550 2775);
DISPLAY 0.787234 (4550 2775);
FORCEPROP 2 LAST $SEC 1
J 0
(4550 2875);
DISPLAY 0.680851 (4550 2875);
PAINT MONO (4550 2875);
DISPLAY INVISIBLE (4550 2875);
FORCEPROP 2 LAST CDS_SEC 1
J 0
(4550 2875);
DISPLAY 1.021277 (4550 2875);
DISPLAY INVISIBLE (4550 2875);
FORCEPROP 1 LASTPIN (4500 2775) $PN 1
J 0
(4510 2755);
DISPLAY 0.787234 (4510 2755);
FORCEPROP 1 LASTPIN (4500 2575) $PN 2
J 0
(4510 2555);
DISPLAY 0.787234 (4510 2555);
FORCEPROP 1 LAST VOLTAGE 25V
J 0
(4550 2675);
DISPLAY 0.638298 (4550 2675);
FORCEPROP 1 LAST VALUE 0.1UF
J 0
(4550 2725);
DISPLAY 0.638298 (4550 2725);
FORCEPROP 1 LAST PACK_TYPE 0402
J 0
(4550 2525);
DISPLAY 0.638298 (4550 2525);
FORCEPROP 1 LAST MATERIAL X7R
J 0
(4550 2575);
DISPLAY 0.638298 (4550 2575);
FORCEPROP 1 LAST TOLERANCE 10%
J 0
(4550 2625);
DISPLAY 0.638298 (4550 2625);
FORCEPROP 2 LAST CDS_LIB pure_quanta
J 0
(4500 2675);
PAINT MONO (4500 2675);
DISPLAY INVISIBLE (4500 2675);
FORCEPROP 1 LAST PATH I87
J 0
(4550 2825);
DISPLAY 0.978723 (4550 2825);
PAINT WHITE (4550 2825);
DISPLAY INVISIBLE (4550 2825);
FORCEPROP 1 LAST PART_NUMBER CH4104K1B00
J 0
(4550 2525);
DISPLAY 0.808511 (4550 2525);
DISPLAY INVISIBLE (4550 2525);
FORCEADD Q_CAP..1
(4750 2675);
FORCEPROP 1 LAST LOCATION C1283
J 0
(4800 2775);
DISPLAY 0.787234 (4800 2775);
FORCEPROP 2 LAST $SEC 1
J 0
(4800 2875);
DISPLAY 0.680851 (4800 2875);
PAINT MONO (4800 2875);
DISPLAY INVISIBLE (4800 2875);
FORCEPROP 2 LAST CDS_SEC 1
J 0
(4800 2875);
DISPLAY 1.021277 (4800 2875);
DISPLAY INVISIBLE (4800 2875);
FORCEPROP 1 LASTPIN (4750 2775) $PN 1
J 0
(4760 2755);
DISPLAY 0.787234 (4760 2755);
FORCEPROP 1 LASTPIN (4750 2575) $PN 2
J 0
(4760 2555);
DISPLAY 0.787234 (4760 2555);
FORCEPROP 1 LAST VALUE 0.1UF
J 0
(4800 2725);
DISPLAY 0.638298 (4800 2725);
FORCEPROP 1 LAST VOLTAGE 25V
J 0
(4800 2675);
DISPLAY 0.638298 (4800 2675);
FORCEPROP 1 LAST MATERIAL X7R
J 0
(4800 2575);
DISPLAY 0.638298 (4800 2575);
FORCEPROP 1 LAST PACK_TYPE 0402
J 0
(4800 2525);
DISPLAY 0.638298 (4800 2525);
FORCEPROP 1 LAST TOLERANCE 10%
J 0
(4800 2625);
DISPLAY 0.638298 (4800 2625);
FORCEPROP 2 LAST CDS_LIB pure_quanta
J 0
(4750 2675);
PAINT MONO (4750 2675);
DISPLAY INVISIBLE (4750 2675);
FORCEPROP 1 LAST PATH I88
J 0
(4800 2825);
DISPLAY 0.978723 (4800 2825);
PAINT WHITE (4800 2825);
DISPLAY INVISIBLE (4800 2825);
FORCEPROP 1 LAST PART_NUMBER CH4104K1B00
J 0
(4800 2525);
DISPLAY 0.808511 (4800 2525);
DISPLAY INVISIBLE (4800 2525);
FORCEADD UNIVERSAL_POWER..1
(4500 3025);
FORCEPROP 3 LASTPIN (4500 2975) SIG_NAME P3V3_E1S_0\g
J 0
(4510 2985);
DISPLAY 0.659574 (4510 2985);
PAINT MONO (4510 2985);
DISPLAY INVISIBLE (4510 2985);
FORCEPROP 1 LAST HDL_POWER P3V3_E1S_0
J 1
(4500 3075);
DISPLAY 0.872340 (4500 3075);
PAINT GREEN (4500 3075);
FORCEPROP 2 LAST CDS_LIB pure_quanta_power
J 0
(4500 3025);
PAINT MONO (4500 3025);
DISPLAY INVISIBLE (4500 3025);
FORCEPROP 1 LAST PATH I89
J 0
(4550 3050);
DISPLAY 0.872340 (4550 3050);
PAINT AQUA (4550 3050);
DISPLAY INVISIBLE (4550 3050);
FORCEADD OFFPAGE..2
(-2225 2375);
FORCEPROP 2 LAST $XR0 145 
J 0
(-2036 2375);
DISPLAY 0.638298 (-2036 2375);
PAINT MONO (-2036 2375);
FORCEPROP 2 LAST CDS_LIB standard
J 0
(-2225 2375);
DISPLAY INVISIBLE (-2225 2375);
FORCEPROP 1 LAST OFFPAGE TRUE
J 0
(-1900 2250);
DISPLAY 0.872340 (-1900 2250);
PAINT GREEN (-1900 2250);
DISPLAY INVISIBLE (-1900 2250);
FORCEPROP 1 LAST COMMENT_BODY TRUE
J 0
(-2270 2280);
DISPLAY 0.872340 (-2270 2280);
PAINT GREEN (-2270 2280);
DISPLAY INVISIBLE (-2270 2280);
FORCEPROP 2 LAST PATH I9
J 0
(-2025 2425);
DISPLAY 0.680851 (-2025 2425);
DISPLAY INVISIBLE (-2025 2425);
FORCEADD SCONN56_123276793..1
(650 3725);
FORCEPROP 1 LAST LOCATION J90
J 0
(80 4906);
DISPLAY 0.723404 (80 4906);
PAINT GREEN (80 4906);
FORCEPROP 0 LAST $SEC 1
J 0
(100 5050);
DISPLAY 0.680851 (100 5050);
PAINT MONO (100 5050);
DISPLAY INVISIBLE (100 5050);
FORCEPROP 0 LAST CDS_SEC 1
J 0
(100 5050);
DISPLAY 1.021277 (100 5050);
DISPLAY INVISIBLE (100 5050);
FORCEPROP 0 LASTPIN (-75 4100) $PN B9
J 2
(-85 4110);
DISPLAY 0.680851 (-85 4110);
PAINT MONO (-85 4110);
FORCEPROP 0 LASTPIN (1375 3000) $PN G1
J 0
(1385 3010);
DISPLAY 0.680851 (1385 3010);
PAINT MONO (1385 3010);
FORCEPROP 0 LASTPIN (-75 3000) $PN G2
J 2
(-85 3010);
DISPLAY 0.680851 (-85 3010);
PAINT MONO (-85 3010);
FORCEPROP 0 LASTPIN (1375 4550) $PN A1
J 0
(1385 4560);
DISPLAY 0.680851 (1385 4560);
PAINT MONO (1385 4560);
FORCEPROP 0 LASTPIN (1375 4500) $PN A2
J 0
(1385 4510);
DISPLAY 0.680851 (1385 4510);
PAINT MONO (1385 4510);
FORCEPROP 0 LASTPIN (1375 4450) $PN A3
J 0
(1385 4460);
DISPLAY 0.680851 (1385 4460);
PAINT MONO (1385 4460);
FORCEPROP 0 LASTPIN (1375 4400) $PN A4
J 0
(1385 4410);
DISPLAY 0.680851 (1385 4410);
PAINT MONO (1385 4410);
FORCEPROP 0 LASTPIN (1375 4350) $PN A5
J 0
(1385 4360);
DISPLAY 0.680851 (1385 4360);
PAINT MONO (1385 4360);
FORCEPROP 0 LASTPIN (1375 4300) $PN A6
J 0
(1385 4310);
DISPLAY 0.680851 (1385 4310);
PAINT MONO (1385 4310);
FORCEPROP 0 LASTPIN (1375 3850) $PN A13
J 0
(1385 3860);
DISPLAY 0.680851 (1385 3860);
PAINT MONO (1385 3860);
FORCEPROP 0 LASTPIN (1375 3700) $PN A16
J 0
(1385 3710);
DISPLAY 0.680851 (1385 3710);
PAINT MONO (1385 3710);
FORCEPROP 0 LASTPIN (1375 3550) $PN A19
J 0
(1385 3560);
DISPLAY 0.680851 (1385 3560);
PAINT MONO (1385 3560);
FORCEPROP 0 LASTPIN (1375 3400) $PN A22
J 0
(1385 3410);
DISPLAY 0.680851 (1385 3410);
PAINT MONO (1385 3410);
FORCEPROP 0 LASTPIN (1375 3250) $PN A25
J 0
(1385 3260);
DISPLAY 0.680851 (1385 3260);
PAINT MONO (1385 3260);
FORCEPROP 0 LASTPIN (1375 3100) $PN A28
J 0
(1385 3110);
DISPLAY 0.680851 (1385 3110);
PAINT MONO (1385 3110);
FORCEPROP 0 LASTPIN (-75 3850) $PN B13
J 2
(-85 3860);
DISPLAY 0.680851 (-85 3860);
PAINT MONO (-85 3860);
FORCEPROP 0 LASTPIN (-75 3700) $PN B16
J 2
(-85 3710);
DISPLAY 0.680851 (-85 3710);
PAINT MONO (-85 3710);
FORCEPROP 0 LASTPIN (-75 3550) $PN B19
J 2
(-85 3560);
DISPLAY 0.680851 (-85 3560);
PAINT MONO (-85 3560);
FORCEPROP 0 LASTPIN (-75 3400) $PN B22
J 2
(-85 3410);
DISPLAY 0.680851 (-85 3410);
PAINT MONO (-85 3410);
FORCEPROP 0 LASTPIN (-75 3250) $PN B25
J 2
(-85 3260);
DISPLAY 0.680851 (-85 3260);
PAINT MONO (-85 3260);
FORCEPROP 0 LASTPIN (-75 3100) $PN B28
J 2
(-85 3110);
DISPLAY 0.680851 (-85 3110);
PAINT MONO (-85 3110);
FORCEPROP 0 LASTPIN (1375 4050) $PN A10
J 0
(1385 4060);
DISPLAY 0.680851 (1385 4060);
PAINT MONO (1385 4060);
FORCEPROP 0 LASTPIN (-75 4200) $PN B7
J 2
(-85 4210);
DISPLAY 0.680851 (-85 4210);
PAINT MONO (-85 4210);
FORCEPROP 0 LASTPIN (-75 4000) $PN B11
J 2
(-85 4010);
DISPLAY 0.680851 (-85 4010);
PAINT MONO (-85 4010);
FORCEPROP 0 LASTPIN (-75 4550) $PN B1
J 2
(-85 4560);
DISPLAY 0.680851 (-85 4560);
PAINT MONO (-85 4560);
FORCEPROP 0 LASTPIN (-75 4500) $PN B2
J 2
(-85 4510);
DISPLAY 0.680851 (-85 4510);
PAINT MONO (-85 4510);
FORCEPROP 0 LASTPIN (-75 4450) $PN B3
J 2
(-85 4460);
DISPLAY 0.680851 (-85 4460);
PAINT MONO (-85 4460);
FORCEPROP 0 LASTPIN (-75 4400) $PN B4
J 2
(-85 4410);
DISPLAY 0.680851 (-85 4410);
PAINT MONO (-85 4410);
FORCEPROP 0 LASTPIN (-75 4350) $PN B5
J 2
(-85 4360);
DISPLAY 0.680851 (-85 4360);
PAINT MONO (-85 4360);
FORCEPROP 0 LASTPIN (-75 4300) $PN B6
J 2
(-85 4310);
DISPLAY 0.680851 (-85 4310);
PAINT MONO (-85 4310);
FORCEPROP 0 LASTPIN (1375 3650) $PN A17
J 0
(1385 3660);
DISPLAY 0.680851 (1385 3660);
PAINT MONO (1385 3660);
FORCEPROP 0 LASTPIN (1375 3500) $PN A20
J 0
(1385 3510);
DISPLAY 0.680851 (1385 3510);
PAINT MONO (1385 3510);
FORCEPROP 0 LASTPIN (1375 3350) $PN A23
J 0
(1385 3360);
DISPLAY 0.680851 (1385 3360);
PAINT MONO (1385 3360);
FORCEPROP 0 LASTPIN (1375 3200) $PN A26
J 0
(1385 3210);
DISPLAY 0.680851 (1385 3210);
PAINT MONO (1385 3210);
FORCEPROP 0 LASTPIN (1375 3600) $PN A18
J 0
(1385 3610);
DISPLAY 0.680851 (1385 3610);
PAINT MONO (1385 3610);
FORCEPROP 0 LASTPIN (1375 3450) $PN A21
J 0
(1385 3460);
DISPLAY 0.680851 (1385 3460);
PAINT MONO (1385 3460);
FORCEPROP 0 LASTPIN (1375 3300) $PN A24
J 0
(1385 3310);
DISPLAY 0.680851 (1385 3310);
PAINT MONO (1385 3310);
FORCEPROP 0 LASTPIN (1375 3150) $PN A27
J 0
(1385 3160);
DISPLAY 0.680851 (1385 3160);
PAINT MONO (1385 3160);
FORCEPROP 0 LASTPIN (-75 4050) $PN B10
J 2
(-85 4060);
DISPLAY 0.680851 (-85 4060);
PAINT MONO (-85 4060);
FORCEPROP 0 LASTPIN (1375 4000) $PN A11
J 0
(1385 4010);
DISPLAY 0.680851 (1385 4010);
PAINT MONO (1385 4010);
FORCEPROP 0 LASTPIN (-75 3650) $PN B17
J 2
(-85 3660);
DISPLAY 0.680851 (-85 3660);
PAINT MONO (-85 3660);
FORCEPROP 0 LASTPIN (-75 3500) $PN B20
J 2
(-85 3510);
DISPLAY 0.680851 (-85 3510);
PAINT MONO (-85 3510);
FORCEPROP 0 LASTPIN (-75 3350) $PN B23
J 2
(-85 3360);
DISPLAY 0.680851 (-85 3360);
PAINT MONO (-85 3360);
FORCEPROP 0 LASTPIN (-75 3200) $PN B26
J 2
(-85 3210);
DISPLAY 0.680851 (-85 3210);
PAINT MONO (-85 3210);
FORCEPROP 0 LASTPIN (-75 3600) $PN B18
J 2
(-85 3610);
DISPLAY 0.680851 (-85 3610);
PAINT MONO (-85 3610);
FORCEPROP 0 LASTPIN (-75 3450) $PN B21
J 2
(-85 3460);
DISPLAY 0.680851 (-85 3460);
PAINT MONO (-85 3460);
FORCEPROP 0 LASTPIN (-75 3300) $PN B24
J 2
(-85 3310);
DISPLAY 0.680851 (-85 3310);
PAINT MONO (-85 3310);
FORCEPROP 0 LASTPIN (-75 3150) $PN B27
J 2
(-85 3160);
DISPLAY 0.680851 (-85 3160);
PAINT MONO (-85 3160);
FORCEPROP 0 LASTPIN (1375 3950) $PN A12
J 0
(1385 3960);
DISPLAY 0.680851 (1385 3960);
PAINT MONO (1385 3960);
FORCEPROP 0 LASTPIN (-75 3950) $PN B12
J 2
(-85 3960);
DISPLAY 0.680851 (-85 3960);
PAINT MONO (-85 3960);
FORCEPROP 0 LASTPIN (-75 3800) $PN B14
J 2
(-85 3810);
DISPLAY 0.680851 (-85 3810);
PAINT MONO (-85 3810);
FORCEPROP 0 LASTPIN (1375 3800) $PN A14
J 0
(1385 3810);
DISPLAY 0.680851 (1385 3810);
PAINT MONO (1385 3810);
FORCEPROP 0 LASTPIN (-75 3750) $PN B15
J 2
(-85 3760);
DISPLAY 0.680851 (-85 3760);
PAINT MONO (-85 3760);
FORCEPROP 0 LASTPIN (1375 3750) $PN A15
J 0
(1385 3760);
DISPLAY 0.680851 (1385 3760);
PAINT MONO (1385 3760);
FORCEPROP 0 LASTPIN (-75 4150) $PN B8
J 2
(-85 4160);
DISPLAY 0.680851 (-85 4160);
PAINT MONO (-85 4160);
FORCEPROP 0 LASTPIN (1375 4200) $PN A7
J 0
(1385 4210);
DISPLAY 0.680851 (1385 4210);
PAINT MONO (1385 4210);
FORCEPROP 0 LASTPIN (1375 4150) $PN A8
J 0
(1385 4160);
DISPLAY 0.680851 (1385 4160);
PAINT MONO (1385 4160);
FORCEPROP 0 LASTPIN (1375 4100) $PN A9
J 0
(1385 4110);
DISPLAY 0.680851 (1385 4110);
PAINT MONO (1385 4110);
FORCEPROP 2 LAST PART_TYPE SMLF
J 0
(100 5000);
DISPLAY 1.021277 (100 5000);
FORCEPROP 2 LAST VALUE SCONN56_1-2327679-3
J 0
(100 4950);
DISPLAY 1.021277 (100 4950);
FORCEPROP 1 LAST MATERIAL IO
J 0
(80 4632);
DISPLAY 0.723404 (80 4632);
PAINT GREEN (80 4632);
FORCEPROP 1 LAST CDS_LMAN_SYM_OUTLINE -575,875,575,-875
J 0
(650 3725);
DISPLAY 0.468085 (650 3725);
PAINT GREEN (650 3725);
DISPLAY INVISIBLE (650 3725);
FORCEPROP 1 LAST NEEDS_NO_SIZE TRUE
J 0
(650 3725);
DISPLAY 0.723404 (650 3725);
PAINT GREEN (650 3725);
DISPLAY INVISIBLE (650 3725);
FORCEPROP 2 LAST CDS_LIB pure_quanta
J 0
(650 3725);
DISPLAY INVISIBLE (650 3725);
FORCEPROP 1 LAST PATH I90
J 0
(650 3725);
DISPLAY 0.723404 (650 3725);
PAINT GREEN (650 3725);
DISPLAY INVISIBLE (650 3725);
FORCEPROP 1 LAST PART_NUMBER DFHS56FS022
J 0
(80 4759);
DISPLAY 0.723404 (80 4759);
PAINT GREEN (80 4759);
DISPLAY INVISIBLE (80 4759);
FORCEADD UNIVERSAL_GND..1
R 2
(-2875 -100);
FORCEPROP 3 LASTPIN (-2875 -50) SIG_NAME GND\g
J 0
(-2865 -40);
DISPLAY 0.659574 (-2865 -40);
PAINT MONO (-2865 -40);
DISPLAY INVISIBLE (-2865 -40);
FORCEPROP 2 LAST CDS_LIB pure_quanta_power
J 0
(-2875 -100);
DISPLAY INVISIBLE (-2875 -100);
FORCEPROP 1 LAST HDL_POWER GND
J 1
(-2900 -175);
DISPLAY 0.872340 (-2900 -175);
PAINT GREEN (-2900 -175);
DISPLAY INVISIBLE (-2900 -175);
FORCEPROP 1 LAST PATH I91
J 2
(-2950 -100);
DISPLAY 0.872340 (-2950 -100);
PAINT AQUA (-2950 -100);
DISPLAY INVISIBLE (-2950 -100);
FORCEADD UNIVERSAL_GND..1
R 2
(-700 -100);
FORCEPROP 3 LASTPIN (-700 -50) SIG_NAME GND\g
J 0
(-690 -40);
DISPLAY 0.659574 (-690 -40);
PAINT MONO (-690 -40);
DISPLAY INVISIBLE (-690 -40);
FORCEPROP 2 LAST CDS_LIB pure_quanta_power
J 0
(-700 -100);
DISPLAY INVISIBLE (-700 -100);
FORCEPROP 1 LAST HDL_POWER GND
J 1
(-725 -175);
DISPLAY 0.872340 (-725 -175);
PAINT GREEN (-725 -175);
DISPLAY INVISIBLE (-725 -175);
FORCEPROP 1 LAST PATH I92
J 2
(-775 -100);
DISPLAY 0.872340 (-775 -100);
PAINT AQUA (-775 -100);
DISPLAY INVISIBLE (-775 -100);
FORCEADD OFFPAGE..1
(-3925 400);
FORCEPROP 2 LAST $XR0 80 
J 0
(-4176 400);
DISPLAY 0.638298 (-4176 400);
PAINT MONO (-4176 400);
FORCEPROP 2 LAST CDS_LIB standard
J 0
(-3925 400);
DISPLAY INVISIBLE (-3925 400);
FORCEPROP 1 LAST OFFPAGE TRUE
J 0
(-3600 275);
DISPLAY 0.872340 (-3600 275);
PAINT GREEN (-3600 275);
DISPLAY INVISIBLE (-3600 275);
FORCEPROP 1 LAST COMMENT_BODY TRUE
J 0
(-3800 300);
DISPLAY 0.872340 (-3800 300);
PAINT GREEN (-3800 300);
DISPLAY INVISIBLE (-3800 300);
FORCEPROP 2 LAST PATH I93
J 0
(-3875 475);
DISPLAY 0.680851 (-3875 475);
DISPLAY INVISIBLE (-3875 475);
FORCEADD Q_RES..1
(-3125 400);
FORCEPROP 1 LAST LOCATION R955
J 0
(-3175 450);
DISPLAY 0.489362 (-3175 450);
PAINT SKYBLUE (-3175 450);
FORCEPROP 2 LAST $SEC 1
J 0
(-3175 600);
DISPLAY 0.680851 (-3175 600);
PAINT MONO (-3175 600);
DISPLAY INVISIBLE (-3175 600);
FORCEPROP 2 LAST CDS_SEC 1
J 0
(-3175 600);
DISPLAY 0.680851 (-3175 600);
DISPLAY INVISIBLE (-3175 600);
FORCEPROP 1 LASTPIN (-3225 400) $PN 1
J 0
(-3213 412);
DISPLAY 0.489362 (-3213 412);
PAINT MONO (-3213 412);
FORCEPROP 1 LASTPIN (-3025 400) $PN 2
J 0
(-3063 412);
DISPLAY 0.489362 (-3063 412);
PAINT MONO (-3063 412);
FORCEPROP 1 LAST VALUE 0
J 2
(-3025 400);
DISPLAY 0.489362 (-3025 400);
PAINT SKYBLUE (-3025 400);
FORCEPROP 1 LAST MATERIAL CHIP
J 0
(-2975 400);
DISPLAY 0.489362 (-2975 400);
PAINT SKYBLUE (-2975 400);
FORCEPROP 1 LAST PACK_TYPE 0402LF
J 0
(-3050 350);
DISPLAY 0.489362 (-3050 350);
PAINT SKYBLUE (-3050 350);
DISPLAY INVISIBLE (-3050 350);
FORCEPROP 1 LAST TOLERANCE 5%
J 0
(-3125 350);
DISPLAY 0.489362 (-3125 350);
PAINT SKYBLUE (-3125 350);
DISPLAY INVISIBLE (-3125 350);
FORCEPROP 1 LAST WATTAGE 1/16W
J 2
(-3150 300);
DISPLAY 0.489362 (-3150 300);
PAINT SKYBLUE (-3150 300);
DISPLAY INVISIBLE (-3150 300);
FORCEPROP 2 LAST CDS_LIB pure_quanta
J 0
(-3125 400);
DISPLAY INVISIBLE (-3125 400);
FORCEPROP 2 LAST BOM_COST OCP3.0 
J 0
(-3050 500);
DISPLAY 0.680851 (-3050 500);
DISPLAY INVISIBLE (-3050 500);
FORCEPROP 1 LAST PATH I94
J 0
(-3175 550);
DISPLAY 0.978723 (-3175 550);
PAINT WHITE (-3175 550);
DISPLAY INVISIBLE (-3175 550);
FORCEPROP 1 LAST PART_NUMBER CS00002JB13
J 0
(-3050 450);
DISPLAY 0.489362 (-3050 450);
PAINT SKYBLUE (-3050 450);
DISPLAY INVISIBLE (-3050 450);
FORCEADD Q_RES..2
(-2875 125);
FORCEPROP 1 LAST LOCATION R999
J 0
(-2830 250);
DISPLAY 0.489362 (-2830 250);
PAINT SKYBLUE (-2830 250);
FORCEPROP 2 LAST $SEC 1
J 0
(-2825 350);
DISPLAY 0.680851 (-2825 350);
PAINT MONO (-2825 350);
DISPLAY INVISIBLE (-2825 350);
FORCEPROP 2 LAST CDS_SEC 1
J 0
(-2825 350);
DISPLAY 0.680851 (-2825 350);
DISPLAY INVISIBLE (-2825 350);
FORCEPROP 1 LASTPIN (-2875 225) $PN 1
J 0
(-2870 187);
DISPLAY 0.489362 (-2870 187);
PAINT MONO (-2870 187);
FORCEPROP 1 LASTPIN (-2875 25) $PN 2
J 0
(-2870 35);
DISPLAY 0.489362 (-2870 35);
PAINT MONO (-2870 35);
FORCEPROP 1 LAST TOLERANCE 5%
J 0
(-2830 150);
DISPLAY 0.489362 (-2830 150);
PAINT SKYBLUE (-2830 150);
FORCEPROP 1 LAST WATTAGE 1/16W
J 0
(-2835 100);
DISPLAY 0.489362 (-2835 100);
PAINT SKYBLUE (-2835 100);
FORCEPROP 1 LAST PACK_TYPE 0402LF
J 0
(-2835 -50);
DISPLAY 0.489362 (-2835 -50);
PAINT SKYBLUE (-2835 -50);
FORCEPROP 1 LAST VALUE 4.7K
J 0
(-2830 200);
DISPLAY 0.489362 (-2830 200);
PAINT SKYBLUE (-2830 200);
FORCEPROP 1 LAST MATERIAL CHIP
J 0
(-2835 50);
DISPLAY 0.489362 (-2835 50);
PAINT SKYBLUE (-2835 50);
FORCEPROP 2 LAST BOM_COST OCP3.0 
J 0
(-2825 300);
DISPLAY 0.680851 (-2825 300);
DISPLAY INVISIBLE (-2825 300);
FORCEPROP 2 LAST CDS_LIB pure_quanta
J 0
(-2875 125);
DISPLAY INVISIBLE (-2875 125);
FORCEPROP 1 LAST PATH I95
J 0
(-2825 300);
DISPLAY 0.978723 (-2825 300);
PAINT WHITE (-2825 300);
DISPLAY INVISIBLE (-2825 300);
FORCEPROP 1 LAST PART_NUMBER CS24702JB10
J 0
(-2835 0);
DISPLAY 0.489362 (-2835 0);
PAINT SKYBLUE (-2835 0);
DISPLAY INVISIBLE (-2835 0);
FORCEADD UNIVERSAL_GND..1
R 2
(-2125 200);
FORCEPROP 3 LASTPIN (-2125 250) SIG_NAME GND\g
J 0
(-2115 260);
DISPLAY 0.659574 (-2115 260);
PAINT MONO (-2115 260);
DISPLAY INVISIBLE (-2115 260);
FORCEPROP 2 LAST CDS_LIB pure_quanta_power
J 0
(-2125 200);
DISPLAY INVISIBLE (-2125 200);
FORCEPROP 1 LAST HDL_POWER GND
J 1
(-2150 125);
DISPLAY 0.872340 (-2150 125);
PAINT GREEN (-2150 125);
DISPLAY INVISIBLE (-2150 125);
FORCEPROP 1 LAST PATH I96
J 2
(-2200 200);
DISPLAY 0.872340 (-2200 200);
PAINT AQUA (-2200 200);
DISPLAY INVISIBLE (-2200 200);
FORCEADD 74LVC1G17GW..1
(-1925 400);
FORCEPROP 1 LAST LOCATION U44
J 0
(-2059 709);
DISPLAY 0.489362 (-2059 709);
PAINT SKYBLUE (-2059 709);
FORCEPROP 2 LAST $SEC 1
J 0
(-2050 850);
DISPLAY 0.680851 (-2050 850);
PAINT MONO (-2050 850);
DISPLAY INVISIBLE (-2050 850);
FORCEPROP 2 LAST CDS_SEC 1
J 0
(-2050 850);
DISPLAY 0.680851 (-2050 850);
DISPLAY INVISIBLE (-2050 850);
FORCEPROP 2 LASTPIN (-2100 400) $PN 2
J 2
(-2110 410);
DISPLAY 0.489362 (-2110 410);
PAINT MONO (-2110 410);
FORCEPROP 2 LASTPIN (-2100 300) $PN 3
J 2
(-2110 310);
DISPLAY 0.489362 (-2110 310);
PAINT MONO (-2110 310);
FORCEPROP 2 LASTPIN (-1750 300) $PN 1
J 0
(-1740 310);
DISPLAY 0.489362 (-1740 310);
PAINT MONO (-1740 310);
FORCEPROP 2 LASTPIN (-2100 500) $PN 5
J 2
(-2110 510);
DISPLAY 0.489362 (-2110 510);
PAINT MONO (-2110 510);
FORCEPROP 2 LASTPIN (-1750 400) $PN 4
J 0
(-1740 410);
DISPLAY 0.489362 (-1740 410);
PAINT MONO (-1740 410);
FORCEPROP 2 LAST VALUE 74LVC1G17GW
J 0
(-2050 750);
DISPLAY 0.489362 (-2050 750);
PAINT SKYBLUE (-2050 750);
FORCEPROP 1 LAST MATERIAL IC
J 0
(-2059 554);
DISPLAY 0.489362 (-2059 554);
PAINT SKYBLUE (-2059 554);
FORCEPROP 2 LAST PART_TYPE SMLF
J 0
(-2050 800);
DISPLAY 0.680851 (-2050 800);
FORCEPROP 2 LAST CDS_LIB pure_quanta
J 0
(-1925 400);
DISPLAY INVISIBLE (-1925 400);
FORCEPROP 1 LAST PIN_NAMES_ROTATE True
J 0
(-1925 400);
DISPLAY 0.489362 (-1925 400);
PAINT GREEN (-1925 400);
DISPLAY INVISIBLE (-1925 400);
FORCEPROP 1 LAST CDS_LMAN_SYM_OUTLINE -125,150,125,-150
J 0
(-1925 400);
DISPLAY 0.468085 (-1925 400);
PAINT GREEN (-1925 400);
DISPLAY INVISIBLE (-1925 400);
FORCEPROP 1 LAST PATH I97
J 0
(-1800 250);
DISPLAY 0.723404 (-1800 250);
PAINT GREEN (-1800 250);
DISPLAY INVISIBLE (-1800 250);
FORCEPROP 1 LAST PART_NUMBER AL1G0017K01
J 0
(-2059 634);
DISPLAY 0.489362 (-2059 634);
PAINT SKYBLUE (-2059 634);
DISPLAY INVISIBLE (-2059 634);
FORCEADD UNIVERSAL_GND..1
R 2
(-2275 500);
FORCEPROP 3 LASTPIN (-2275 550) SIG_NAME GND\g
J 0
(-2265 560);
DISPLAY 0.659574 (-2265 560);
PAINT MONO (-2265 560);
DISPLAY INVISIBLE (-2265 560);
FORCEPROP 2 LAST CDS_LIB pure_quanta_power
J 0
(-2275 500);
DISPLAY INVISIBLE (-2275 500);
FORCEPROP 1 LAST HDL_POWER GND
J 1
(-2300 425);
DISPLAY 0.872340 (-2300 425);
PAINT GREEN (-2300 425);
DISPLAY INVISIBLE (-2300 425);
FORCEPROP 1 LAST PATH I98
J 2
(-2350 500);
DISPLAY 0.872340 (-2350 500);
PAINT AQUA (-2350 500);
DISPLAY INVISIBLE (-2350 500);
FORCEADD Q_CAP..1
R 2
(-2275 700);
FORCEPROP 1 LAST LOCATION C508
J 2
(-2325 825);
DISPLAY 0.489362 (-2325 825);
PAINT SKYBLUE (-2325 825);
FORCEPROP 0 LAST $SEC 1
J 0
(-2325 875);
DISPLAY 0.680851 (-2325 875);
PAINT MONO (-2325 875);
DISPLAY INVISIBLE (-2325 875);
FORCEPROP 0 LAST CDS_SEC 1
J 0
(-2325 875);
DISPLAY 1.021277 (-2325 875);
DISPLAY INVISIBLE (-2325 875);
FORCEPROP 1 LASTPIN (-2275 800) $PN 1
J 2
(-2285 780);
DISPLAY 0.489362 (-2285 780);
PAINT MONO (-2285 780);
FORCEPROP 1 LASTPIN (-2275 600) $PN 2
J 2
(-2285 580);
DISPLAY 0.489362 (-2285 580);
PAINT MONO (-2285 580);
FORCEPROP 1 LAST TOLERANCE 10%
J 2
(-2325 700);
DISPLAY 0.489362 (-2325 700);
PAINT SKYBLUE (-2325 700);
FORCEPROP 1 LAST VOLTAGE 25V
J 2
(-2325 750);
DISPLAY 0.489362 (-2325 750);
PAINT SKYBLUE (-2325 750);
FORCEPROP 1 LAST MATERIAL X7R
J 2
(-2325 650);
DISPLAY 0.489362 (-2325 650);
PAINT SKYBLUE (-2325 650);
FORCEPROP 1 LAST VALUE 0.1UF
J 2
(-2325 800);
DISPLAY 0.489362 (-2325 800);
PAINT SKYBLUE (-2325 800);
FORCEPROP 1 LAST PACK_TYPE 0402
J 2
(-2325 600);
DISPLAY 0.489362 (-2325 600);
PAINT SKYBLUE (-2325 600);
FORCEPROP 2 LAST CDS_LIB pure_quanta
J 0
(-2275 700);
DISPLAY INVISIBLE (-2275 700);
FORCEPROP 1 LAST PATH I99
J 2
(-2325 850);
DISPLAY 0.978723 (-2325 850);
PAINT WHITE (-2325 850);
DISPLAY INVISIBLE (-2325 850);
FORCEPROP 1 LAST PART_NUMBER CH4104K1B00
J 2
(-2325 550);
DISPLAY 0.489362 (-2325 550);
PAINT SKYBLUE (-2325 550);
DISPLAY INVISIBLE (-2325 550);
FORCEADD DNS..2
(2950 -350);
PAINT RED (2950 -350);
FORCEPROP 2 LAST CDS_LIB mstr_misc
J 0
(2950 -350);
DISPLAY INVISIBLE (2950 -350);
FORCEPROP 1 LAST COMMENT_BODY TRUE
J 0
(2950 -350);
DISPLAY INVISIBLE (2950 -350);
FORCEADD DESIGN_NOTE..1
(-3425 4650);
FORCEPROP 0 LAST S1 DP/DN SWAP TX[0:1] RX[0]
J 0
(-3625 4500);
DISPLAY 1.021277 (-3625 4500);
PAINT SKYBLUE (-3625 4500);
FORCEPROP 2 LAST CDS_LIB pure_quanta_power
J 0
(-3425 4650);
DISPLAY INVISIBLE (-3425 4650);
FORCEPROP 1 LAST COMMENT_BODY TRUE
J 0
(-3400 4750);
DISPLAY 0.978723 (-3400 4750);
DISPLAY INVISIBLE (-3400 4750);
FORCEADD QUANTA_TITLE_BLOCK_C..1
(5025 -1275);
FORCEPROP 0 LAST CDS_CON_LAST_MODIFIED Thu Sep 14 16:12:36 2023
J 0
(3140 -1260);
DISPLAY INVISIBLE (3140 -1260);
FORCEPROP 1 LAST CUSTOM_TXT_CDS <CON_LAST_MODIFIED>
J 0
(3140 -1260);
DISPLAY 0.978723 (3140 -1260);
FORCEPROP 2 LAST CUSTOM_TXT_CDS <XR_PAGE_TITLE>
J 0
(-2865 3975);
DISPLAY 0.638298 (-2865 3975);
PAINT PINK (-2865 3975);
DISPLAY INVISIBLE (-2865 3975);
FORCEPROP 1 LAST CUSTOM_TXT_CDS <NAME_2>
J 0
(1850 -1225);
FORCEPROP 1 LAST CUSTOM_TXT_CDS <NAME_1>
J 0
(1850 -1100);
FORCEPROP 1 LAST CUSTOM_TXT_CDS <Q_NUMBER>
J 0
(3622 -1172);
DISPLAY 1.212766 (3622 -1172);
FORCEPROP 1 LAST CUSTOM_TXT_CDS <Q_PROJ>
J 0
(2643 -1173);
DISPLAY 1.212766 (2643 -1173);
FORCEPROP 1 LAST CUSTOM_TXT_CDS <Q_REV>
J 0
(4841 -1172);
DISPLAY 1.212766 (4841 -1172);
FORCEPROP 1 LAST CUSTOM_TXT_CDS <CON_PAGE_NUM> OF <CON_TOTAL_PAGES>
J 0
(4579 -1257);
DISPLAY 0.978723 (4579 -1257);
FORCEPROP 1 LAST Q_TITLE CPU0 - E1S - 0 CONN
J 0
(-4200 -1200);
DISPLAY 2.446809 (-4200 -1200);
PAINT GREEN (-4200 -1200);
FORCEPROP 2 LAST CDS_LIB pure_quanta
J 0
(5025 -1275);
DISPLAY INVISIBLE (5025 -1275);
FORCEPROP 1 LAST CDS_LMAN_SYM_OUTLINE -9475,6775,100,-125
J 0
(5025 -1275);
DISPLAY 0.468085 (5025 -1275);
PAINT GREEN (5025 -1275);
DISPLAY INVISIBLE (5025 -1275);
FORCEPROP 2 LAST PAGE_BORDER TRUE
J 0
(-2865 3975);
DISPLAY 0.638298 (-2865 3975);
PAINT PINK (-2865 3975);
DISPLAY INVISIBLE (-2865 3975);
FORCEPROP 2 LAST CDS_XR_PAGE_TITLE CR-145 : @T6G_MB_LIB.T6G(SCH_1):PAGE145
J 0
(-2865 3975);
DISPLAY 0.638298 (-2865 3975);
PAINT PINK (-2865 3975);
DISPLAY INVISIBLE (-2865 3975);
FORCEPROP 1 LAST Q_DEPT BU9
J 1
(1262 -1226);
DISPLAY 1.957447 (1262 -1226);
PAINT GREEN (1262 -1226);
DISPLAY INVISIBLE (1262 -1226);
FORCEPROP 1 LAST COMMENT_BODY TRUE
J 0
(5037 -1288);
DISPLAY 0.978723 (5037 -1288);
PAINT GREEN (5037 -1288);
DISPLAY INVISIBLE (5037 -1288);
FORCEADD CAD_NOTE..1
(3100 3075);
FORCEPROP 0 LAST S1 PLACE THE BULK CAPS CLOSE TO SLOT
J 0
(2975 2950);
DISPLAY 0.808511 (2975 2950);
PAINT WHITE (2975 2950);
FORCEPROP 2 LAST CDS_LIB pure_quanta_power
J 0
(3100 3075);
PAINT MONO (3100 3075);
DISPLAY INVISIBLE (3100 3075);
FORCEPROP 1 LAST COMMENT_BODY TRUE
J 0
(3125 3175);
DISPLAY 0.978723 (3125 3175);
DISPLAY INVISIBLE (3125 3175);
FORCEADD DNS..2
(-2895 2620);
PAINT RED (-2895 2620);
FORCEPROP 2 LAST CDS_LIB mstr_misc
J 0
(-2895 2620);
DISPLAY INVISIBLE (-2895 2620);
FORCEPROP 1 LAST COMMENT_BODY TRUE
J 0
(-2895 2620);
DISPLAY INVISIBLE (-2895 2620);
FORCEADD DNS..2
(4000 3675);
PAINT RED (4000 3675);
FORCEPROP 2 LAST CDS_LIB mstr_misc
J 0
(4000 3675);
DISPLAY INVISIBLE (4000 3675);
FORCEPROP 1 LAST COMMENT_BODY TRUE
J 0
(4000 3675);
DISPLAY INVISIBLE (4000 3675);
WIRE 17 -1 (1875 3525)(1875 3375);
WIRE 17 -1 (1875 3675)(1875 3525);
WIRE 17 -1 (1875 3375)(1875 3225);
WIRE 17 -1 (3000 3675)(1875 3675);
FORCEPROP 2 LAST SIG_NAME P3E_CPU0_P4_RX_DP<3:0>
J 0
(2115 3685);
DISPLAY 0.510638 (2115 3685);
PAINT WHITE (2115 3685);
WIRE 17 -1 (2025 3625)(2025 3475);
WIRE 17 -1 (3000 3625)(2025 3625);
FORCEPROP 2 LAST SIG_NAME P3E_CPU0_P4_RX_DN<3:0>
J 0
(2115 3635);
DISPLAY 0.510638 (2115 3635);
PAINT WHITE (2115 3635);
WIRE 17 -1 (2025 3475)(2025 3325);
WIRE 17 -1 (2025 3325)(2025 3175);
WIRE 17 -1 (-525 3525)(-525 3675);
WIRE 17 -1 (-525 3375)(-525 3525);
WIRE 17 -1 (-1475 3675)(-525 3675);
FORCEPROP 2 LAST SIG_NAME P3E_CPU0_P4_TX_C_DP<3:0>
J 0
(-1410 3685);
DISPLAY 0.553191 (-1410 3685);
PAINT WHITE (-1410 3685);
WIRE 17 -1 (-525 3375)(-525 3175);
WIRE 17 -1 (-675 3325)(-675 3475);
WIRE 17 -1 (-675 3325)(-675 3225);
WIRE 17 -1 (-675 3475)(-675 3625);
WIRE 17 -1 (-675 3625)(-1475 3625);
FORCEPROP 2 LAST SIG_NAME P3E_CPU0_P4_TX_C_DN<3:0>
J 0
(-1410 3635);
DISPLAY 0.553191 (-1410 3635);
PAINT WHITE (-1410 3635);
WIRE 16 -1 (-1775 4475)(-1775 4575);
WIRE 16 -1 (2900 4750)(2900 4575);
WIRE 16 -1 (-25 -750)(75 -750);
WIRE 16 -1 (-25 -750)(-25 -925);
WIRE 16 -1 (1100 -450)(1100 -525);
WIRE 16 -1 (-2900 1950)(-2900 2050);
WIRE 16 -1 (4000 3525)(4000 3600);
WIRE 16 -1 (2450 4625)(2450 4575);
WIRE 16 -1 (-2900 2750)(-2900 2850);
WIRE 16 -1 (-2875 -50)(-2875 25);
WIRE 16 -1 (-700 -50)(-700 25);
WIRE 16 -1 (-2275 600)(-2275 550);
WIRE 16 -1 (1375 3100)(1550 3100);
WIRE 16 -1 (1550 3250)(1550 3100);
WIRE 16 -1 (1550 3000)(1550 3100);
WIRE 16 -1 (1550 2850)(1550 3000);
WIRE 16 -1 (1375 3000)(1550 3000);
WIRE 16 -1 (1550 3400)(1550 3250);
WIRE 16 -1 (1375 3250)(1550 3250);
WIRE 16 -1 (1550 3550)(1550 3400);
WIRE 16 -1 (1375 3400)(1550 3400);
WIRE 16 -1 (1550 3700)(1550 3550);
WIRE 16 -1 (1375 3550)(1550 3550);
WIRE 16 -1 (1550 3700)(1550 3850);
WIRE 16 -1 (1375 3700)(1550 3700);
WIRE 16 -1 (1550 4300)(1550 3850);
WIRE 16 -1 (1375 3850)(1550 3850);
WIRE 16 -1 (1550 4300)(1550 4350);
WIRE 16 -1 (1375 4300)(1550 4300);
WIRE 16 -1 (1550 4400)(1550 4350);
WIRE 16 -1 (1375 4350)(1550 4350);
WIRE 16 -1 (1550 4400)(1550 4450);
WIRE 16 -1 (1375 4400)(1550 4400);
WIRE 16 -1 (1550 4450)(1550 4500);
WIRE 16 -1 (1375 4450)(1550 4450);
WIRE 16 -1 (1550 4500)(1550 4550);
WIRE 16 -1 (1375 4500)(1550 4500);
WIRE 16 -1 (1375 4550)(1550 4550);
WIRE 16 -1 (1375 3150)(1925 3150);
WIRE 16 -1 (-250 3100)(-75 3100);
WIRE 16 -1 (-250 3250)(-250 3100);
WIRE 16 -1 (-250 3100)(-250 3000);
WIRE 16 -1 (-250 2850)(-250 3000);
WIRE 16 -1 (-250 3000)(-75 3000);
WIRE 16 -1 (-250 3250)(-250 3400);
WIRE 16 -1 (-250 3250)(-75 3250);
WIRE 16 -1 (-250 3400)(-75 3400);
WIRE 16 -1 (-250 3400)(-250 3550);
WIRE 16 -1 (-250 3550)(-250 3700);
WIRE 16 -1 (-250 3550)(-75 3550);
WIRE 16 -1 (-250 3700)(-250 3850);
WIRE 16 -1 (-250 3700)(-75 3700);
WIRE 16 -1 (-75 3850)(-250 3850);
WIRE 16 -1 (1375 3500)(1775 3500);
WIRE 16 -1 (1375 3600)(1925 3600);
WIRE 16 -1 (1375 3650)(1775 3650);
WIRE 16 -1 (-200 4975)(-200 4550);
WIRE 16 -1 (-200 4550)(-75 4550);
WIRE 16 -1 (-200 4500)(-200 4550);
WIRE 16 -1 (-200 4500)(-75 4500);
WIRE 16 -1 (-200 4450)(-200 4500);
WIRE 16 -1 (-200 4450)(-75 4450);
WIRE 16 -1 (-200 4400)(-200 4450);
WIRE 16 -1 (-200 4400)(-75 4400);
WIRE 16 -1 (-200 4400)(-200 4350);
WIRE 16 -1 (-200 4350)(-75 4350);
WIRE 16 -1 (-200 4300)(-200 4350);
WIRE 16 -1 (-200 4300)(-75 4300);
WIRE 16 -1 (1375 4200)(2975 4200);
FORCEPROP 2 LAST SIG_NAME SMB_E1S_3V3AUX_ISO_SCL
J 0
(1740 4210);
DISPLAY 0.553191 (1740 4210);
PAINT WHITE (1740 4210);
WIRE 16 -1 (1375 4150)(2975 4150);
FORCEPROP 2 LAST SIG_NAME SMB_E1S_3V3AUX_ISO_SDA
J 0
(1740 4160);
DISPLAY 0.553191 (1740 4160);
PAINT WHITE (1740 4160);
WIRE 16 -1 (1375 4100)(2450 4100);
FORCEPROP 2 LAST SIG_NAME RST_SMB_E1S_0_N
J 0
(1740 4110);
DISPLAY 0.553191 (1740 4110);
PAINT WHITE (1740 4110);
WIRE 16 -1 (2975 4100)(2450 4100);
WIRE 16 -1 (2450 4375)(2450 4100);
WIRE 16 -1 (1375 4050)(2975 4050);
FORCEPROP 2 LAST SIG_NAME FM_LED_ACTIVE_E1S_0_BUF
J 0
(1740 4060);
DISPLAY 0.553191 (1740 4060);
PAINT WHITE (1740 4060);
WIRE 16 -1 (2975 3950)(1375 3950);
FORCEPROP 2 LAST SIG_NAME E1S_0_PRSNT_N
J 0
(1740 3960);
DISPLAY 0.553191 (1740 3960);
PAINT WHITE (1740 3960);
WIRE 16 -1 (1375 3750)(2925 3750);
FORCEPROP 2 LAST SIG_NAME TP_CLK_100M_E1S_0_DP
J 0
(1740 3760);
DISPLAY 0.553191 (1740 3760);
PAINT WHITE (1740 3760);
FORCEPROP 2 LASTPROP $XRERR UNIQUE?
J 0
(2955 3750);
DISPLAY 0.638298 (2955 3750);
PAINT MONO (2955 3750);
DISPLAY INVISIBLE (2955 3750);
WIRE 16 -1 (1375 3800)(2925 3800);
FORCEPROP 2 LAST SIG_NAME TP_CLK_100M_E1S_0_DN
J 0
(1740 3810);
DISPLAY 0.553191 (1740 3810);
PAINT WHITE (1740 3810);
FORCEPROP 2 LASTPROP $XRERR UNIQUE?
J 0
(2955 3800);
DISPLAY 0.638298 (2955 3800);
PAINT MONO (2955 3800);
DISPLAY INVISIBLE (2955 3800);
WIRE 16 -1 (1375 4000)(2900 4000);
FORCEPROP 2 LAST SIG_NAME E1S_0_PERST1_CLKREQ_N
J 0
(1740 4010);
DISPLAY 0.553191 (1740 4010);
PAINT WHITE (1740 4010);
WIRE 16 -1 (2900 4375)(2900 4000);
WIRE 16 -1 (4000 4000)(2900 4000);
WIRE 16 -1 (4175 4000)(4000 4000);
WIRE 16 -1 (4000 3800)(4000 4000);
WIRE 16 -1 (2475 2775)(2475 2900);
WIRE 16 -1 (2475 2900)(2750 2900);
WIRE 16 -1 (2475 2975)(2475 2900);
WIRE 16 -1 (3150 2900)(2750 2900);
WIRE 16 -1 (2750 2900)(2750 2775);
WIRE 16 -1 (3150 2900)(3425 2900);
WIRE 16 -1 (3150 2900)(3150 2775);
WIRE 16 -1 (3425 2900)(3425 2775);
WIRE 16 -1 (-2125 300)(-2100 300);
WIRE 16 -1 (-2125 250)(-2125 300);
WIRE 16 -1 (4750 2900)(4750 2775);
WIRE 16 -1 (4500 2900)(4750 2900);
WIRE 16 -1 (4500 2975)(4500 2900);
WIRE 16 -1 (4500 2900)(4500 2775);
WIRE 16 -1 (4750 2450)(4750 2575);
WIRE 16 -1 (4750 2375)(4750 2450);
WIRE 16 -1 (4500 2450)(4750 2450);
WIRE 16 -1 (4500 2575)(4500 2450);
WIRE 16 -1 (2475 2575)(2475 2450);
WIRE 16 -1 (2475 2450)(2750 2450);
WIRE 16 -1 (3150 2450)(2750 2450);
WIRE 16 -1 (2750 2450)(2750 2575);
WIRE 16 -1 (3150 2450)(3150 2575);
WIRE 16 -1 (3150 2450)(3425 2450);
WIRE 16 -1 (3425 2450)(3425 2575);
WIRE 16 -1 (3425 2375)(3425 2450);
WIRE 16 -1 (3200 -125)(3200 -250);
WIRE 16 -1 (3200 -125)(2925 -125);
WIRE 16 -1 (2925 -50)(2925 -125);
WIRE 16 -1 (2925 -125)(2925 -250);
WIRE 16 -1 (725 -750)(850 -750);
WIRE 16 -1 (850 -175)(850 -750);
WIRE 16 -1 (1100 -175)(850 -175);
WIRE 16 -1 (1100 -75)(1100 -175);
WIRE 16 -1 (1100 -175)(1100 -250);
WIRE 16 -1 (-500 4800)(-500 4000);
WIRE 16 -1 (-500 4000)(-75 4000);
WIRE 16 -1 (-2275 875)(-2200 875);
WIRE 16 -1 (-2275 800)(-2275 875);
WIRE 16 -1 (-2200 925)(-2200 875);
WIRE 16 -1 (-2200 875)(-2200 500);
WIRE 16 -1 (-2200 500)(-2100 500);
WIRE 16 -1 (2925 -450)(2925 -700);
WIRE 16 -1 (2925 -700)(3325 -700);
WIRE 16 -1 (2000 -700)(2925 -700);
FORCEPROP 2 LAST SIG_NAME RST_SMB_E1S_0_N
J 0
(2365 -690);
DISPLAY 0.702128 (2365 -690);
PAINT WHITE (2365 -690);
WIRE 16 -1 (3200 -450)(3200 -800);
WIRE 16 -1 (3200 -800)(3325 -800);
WIRE 16 -1 (2000 -800)(3200 -800);
FORCEPROP 2 LAST SIG_NAME SMB_PCIE_E1S_ISO_EN
J 0
(2365 -790);
DISPLAY 0.702128 (2365 -790);
PAINT WHITE (2365 -790);
WIRE 16 -1 (-1775 4275)(-1775 4100);
WIRE 16 -1 (-75 4100)(-1775 4100);
FORCEPROP 2 LAST SIG_NAME PU_E1S_0_DUALPORT_EN_N
J 0
(-1410 4110);
DISPLAY 0.553191 (-1410 4110);
PAINT WHITE (-1410 4110);
FORCEPROP 2 LASTPROP $XRERR UNIQUE?
J 0
(-1650 4110);
DISPLAY 0.638298 (-1650 4110);
PAINT MONO (-1650 4110);
DISPLAY INVISIBLE (-1650 4110);
WIRE 16 -1 (-1475 4150)(-75 4150);
FORCEPROP 2 LAST SIG_NAME TP_E1S_0_RFU
J 0
(-1410 4160);
DISPLAY 0.553191 (-1410 4160);
PAINT WHITE (-1410 4160);
FORCEPROP 2 LASTPROP $XRERR UNIQUE?
J 0
(-1715 4150);
DISPLAY 0.638298 (-1715 4150);
PAINT MONO (-1715 4150);
DISPLAY INVISIBLE (-1715 4150);
WIRE 16 -1 (-1750 4050)(-75 4050);
FORCEPROP 2 LAST SIG_NAME RST_PCIE_E1S_PERST_N
J 0
(-1410 4060);
DISPLAY 0.553191 (-1410 4060);
PAINT WHITE (-1410 4060);
FORCEPROP 2 LASTPROP $XRERR UNIQUE?
J 0
(-1650 4060);
DISPLAY 0.638298 (-1650 4060);
PAINT MONO (-1650 4060);
DISPLAY INVISIBLE (-1650 4060);
WIRE 16 -1 (-1475 3800)(-75 3800);
FORCEPROP 2 LAST SIG_NAME CLK_100M_CPU0_CLK12_DN
J 0
(-1410 3810);
DISPLAY 0.553191 (-1410 3810);
PAINT WHITE (-1410 3810);
WIRE 16 -1 (-1475 3750)(-75 3750);
FORCEPROP 2 LAST SIG_NAME CLK_100M_CPU0_CLK12_DP
J 0
(-1435 3760);
DISPLAY 0.553191 (-1435 3760);
PAINT WHITE (-1435 3760);
WIRE 16 -1 (-1475 3950)(-75 3950);
FORCEPROP 2 LAST SIG_NAME E1S_0_PWRDIS
J 0
(-1410 3960);
DISPLAY 0.553191 (-1410 3960);
PAINT WHITE (-1410 3960);
WIRE 16 -1 (-1475 4200)(-75 4200);
FORCEPROP 2 LAST SIG_NAME TP_E1S_0_MFG
J 0
(-1410 4210);
DISPLAY 0.553191 (-1410 4210);
PAINT WHITE (-1410 4210);
FORCEPROP 2 LASTPROP $XRERR UNIQUE?
J 0
(-1715 4200);
DISPLAY 0.638298 (-1715 4200);
PAINT MONO (-1715 4200);
DISPLAY INVISIBLE (-1715 4200);
WIRE 16 -1 (-950 -700)(-1525 -700);
FORCEPROP 0 LAST CDS_PHYS_NET_NAME RST_SMB_SWITCH_N
J 0
(-1500 -658);
PAINT MONO (-1500 -658);
DISPLAY INVISIBLE (-1500 -658);
FORCEPROP 0 LAST SIG_NAME FM_SMB_RST_E1S_0_R_N
J 0
(-1485 -690);
DISPLAY 0.553191 (-1485 -690);
PAINT WHITE (-1485 -690);
WIRE 16 -1 (-3225 400)(-3875 400);
FORCEPROP 0 LAST SIG_NAME FM_LED_ACTIVE_E1S_0
J 0
(-3835 410);
DISPLAY 0.489362 (-3835 410);
WIRE 16 -1 (-2875 225)(-2875 400);
WIRE 16 -1 (-2100 400)(-2875 400);
FORCEPROP 0 LAST SIG_NAME FM_LED_ACTIVE_E1S_0_R
J 0
(-2835 410);
DISPLAY 0.489362 (-2835 410);
FORCEPROP 2 LASTPROP $XRERR UNIQUE?
J 0
(-3075 410);
DISPLAY 0.638298 (-3075 410);
PAINT MONO (-3075 410);
DISPLAY INVISIBLE (-3075 410);
WIRE 16 -1 (-2875 400)(-3025 400);
WIRE 16 -1 (-1750 400)(-925 400);
FORCEPROP 0 LAST SIG_NAME FM_LED_ACTIVE_E1S_0_R_BUF
J 0
(-1660 410);
DISPLAY 0.489362 (-1660 410);
FORCEPROP 2 LASTPROP $XRERR UNIQUE?
J 0
(-1900 410);
DISPLAY 0.638298 (-1900 410);
PAINT MONO (-1900 410);
DISPLAY INVISIBLE (-1900 410);
WIRE 16 -1 (-725 400)(-700 400);
WIRE 16 -1 (-700 400)(150 400);
FORCEPROP 0 LAST SIG_NAME FM_LED_ACTIVE_E1S_0_BUF
J 0
(-410 410);
DISPLAY 0.489362 (-410 410);
WIRE 16 -1 (-700 225)(-700 400);
WIRE 16 -1 (-75 3200)(-575 3200);
WIRE 16 -1 (-575 3450)(-75 3450);
WIRE 16 -1 (-425 3500)(-75 3500);
WIRE 16 -1 (-575 3600)(-75 3600);
WIRE 16 -1 (-2950 4050)(-1950 4050);
FORCEPROP 2 LAST SIG_NAME RST_PERST_E1S_0_N
J 0
(-2885 4060);
DISPLAY 0.553191 (-2885 4060);
PAINT WHITE (-2885 4060);
WIRE 16 -1 (-75 3150)(-425 3150);
WIRE 16 -1 (-575 3300)(-75 3300);
WIRE 16 -1 (-425 3350)(-75 3350);
WIRE 16 -1 (-425 3650)(-75 3650);
WIRE 16 -1 (1375 3300)(1925 3300);
WIRE 16 -1 (1375 3450)(1925 3450);
WIRE 16 -1 (-375 -800)(75 -800);
WIRE 16 -1 (-375 -700)(-375 -800);
WIRE 16 -1 (75 -700)(-375 -700);
WIRE 16 -1 (-375 -700)(-750 -700);
FORCEPROP 0 LAST CDS_PHYS_NET_NAME RST_SMB_E1S_N
J 0
(-725 -658);
PAINT MONO (-725 -658);
DISPLAY INVISIBLE (-725 -658);
FORCEPROP 0 LAST SIG_NAME RST_SMB_E1S_N
J 0
(-435 -690);
DISPLAY 0.702128 (-435 -690);
PAINT WHITE (-435 -690);
FORCEPROP 2 LASTPROP $XRERR UNIQUE?
J 0
(-675 -690);
DISPLAY 0.638298 (-675 -690);
PAINT MONO (-675 -690);
DISPLAY INVISIBLE (-675 -690);
WIRE 16 -1 (725 -700)(1800 -700);
FORCEPROP 0 LAST CDS_PHYS_NET_NAME RST_SMB_BUF_E1S_0_N
J 0
(750 -658);
PAINT MONO (750 -658);
DISPLAY INVISIBLE (750 -658);
FORCEPROP 0 LAST SIG_NAME RST_SMB_BUF_E1S_0_N
J 0
(915 -690);
DISPLAY 0.702128 (915 -690);
PAINT WHITE (915 -690);
FORCEPROP 2 LASTPROP $XRERR UNIQUE?
J 0
(675 -690);
DISPLAY 0.638298 (675 -690);
PAINT MONO (675 -690);
DISPLAY INVISIBLE (675 -690);
WIRE 16 -1 (725 -800)(1800 -800);
FORCEPROP 0 LAST CDS_PHYS_NET_NAME SMB_PCIE_E1S_ISO_EN_R2
J 0
(750 -758);
PAINT MONO (750 -758);
DISPLAY INVISIBLE (750 -758);
FORCEPROP 0 LAST SIG_NAME SMB_PCIE_E1S_ISO_EN_R2
J 0
(915 -790);
DISPLAY 0.702128 (915 -790);
PAINT WHITE (915 -790);
FORCEPROP 2 LASTPROP $XRERR UNIQUE?
J 0
(675 -790);
DISPLAY 0.638298 (675 -790);
PAINT MONO (675 -790);
DISPLAY INVISIBLE (675 -790);
WIRE 16 -1 (1375 3200)(1775 3200);
WIRE 16 -1 (1375 3350)(1775 3350);
WIRE 16 -1 (-2900 2375)(-2275 2375);
FORCEPROP 2 LAST SIG_NAME E1S_0_PWRDIS
J 0
(-2785 2385);
DISPLAY 0.638298 (-2785 2385);
PAINT WHITE (-2785 2385);
WIRE 16 -1 (-2900 2550)(-2900 2375);
WIRE 16 -1 (-2900 2375)(-2900 2250);
DOT 1 (1550 3100);
DOT 1 (2925 -700);
DOT 1 (2450 4100);
DOT 1 (-200 4450);
DOT 1 (-200 4500);
DOT 1 (-700 400);
DOT 1 (-2200 875);
DOT 1 (-2875 400);
DOT 1 (4750 2450);
DOT 1 (4500 2900);
DOT 1 (4000 4000);
DOT 1 (2900 4000);
DOT 1 (1550 4500);
DOT 1 (1550 4400);
DOT 1 (1550 4300);
DOT 1 (3425 2450);
DOT 1 (3150 2900);
DOT 1 (3150 2450);
DOT 1 (2750 2900);
DOT 1 (2750 2450);
DOT 1 (2475 2900);
DOT 1 (2925 -125);
DOT 1 (1550 3850);
DOT 1 (1550 3250);
DOT 1 (1550 3000);
DOT 1 (3200 -800);
DOT 1 (1100 -175);
DOT 1 (-200 4550);
DOT 1 (-200 4400);
DOT 1 (-200 4350);
DOT 1 (-250 3550);
DOT 1 (-250 3400);
DOT 1 (-250 3000);
DOT 1 (-250 3100);
DOT 1 (-2900 2375);
DOT 1 (-375 -700);
DOT 1 (1550 4450);
DOT 1 (1550 3550);
DOT 1 (1550 3700);
DOT 1 (1550 3400);
DOT 1 (-250 3250);
DOT 1 (-250 3700);
DOT 1 (1550 4350);
FORCENOTE
TX[2:0] PN SWAP
(-1950 3350) 0;
DISPLAY LEFT (-1950 3350);
DISPLAY 1.021277 (-1950 3350);
FORCENOTE
RX[3:0] PN SWAP
(2200 3500) 0;
DISPLAY LEFT (2200 3500);
DISPLAY 1.021277 (2200 3500);
QUIT
